FILE_TYPE = MACRO_DRAWING;
SET COLOR_WIRE YELLOW;
SET COLOR_PROP MONO;
SET COLOR_DOT WHITE;
SET COLOR_ARC YELLOW;
SET COLOR_BODY GREEN;
SET COLOR_NOTE MONO;
SET PROP_DISPLAY VALUE;
SET PAGE_NUMBER P62;
FORCEADD OFFPAGE..5
(-6450 500);
FORCEPROP 2 LAST $XR0 87 
J 0
(-6674 500);
DISPLAY 0.638298 (-6674 500);
PAINT MONO (-6674 500);
FORCEPROP 2 LAST $XR1 88 
J 0
(-6764 500);
DISPLAY 0.638298 (-6764 500);
PAINT MONO (-6764 500);
FORCEPROP 2 LAST CDS_LIB mstr_standard
J 0
(-6450 500);
PAINT MONO (-6450 500);
DISPLAY INVISIBLE (-6450 500);
FORCEPROP 1 LAST OFFPAGE TRUE
J 0
(-6125 375);
DISPLAY 1.170213 (-6125 375);
PAINT GREEN (-6125 375);
DISPLAY INVISIBLE (-6125 375);
FORCEPROP 1 LAST COMMENT_BODY TRUE
J 0
(-6350 425);
DISPLAY 1.170213 (-6350 425);
PAINT GREEN (-6350 425);
DISPLAY INVISIBLE (-6350 425);
FORCEPROP 2 LAST PATH I1
J 0
(-6400 575);
DISPLAY 1.021277 (-6400 575);
PAINT ORANGE (-6400 575);
DISPLAY INVISIBLE (-6400 575);
FORCEADD TAP..6
(-5600 800);
FORCEPROP 3 LASTPIN (-5550 800) SIG_NAME M_M_CLK_DP<0>
J 0
(-5540 810);
DISPLAY 0.659574 (-5540 810);
PAINT MONO (-5540 810);
DISPLAY INVISIBLE (-5540 810);
FORCEPROP 1 LASTPIN (-5550 800) BN 0
J 0
(-5602 808);
DISPLAY 0.617021 (-5602 808);
PAINT GREEN (-5602 808);
FORCEPROP 2 LAST CDS_LIB mstr_standard
J 0
(-5600 800);
PAINT MONO (-5600 800);
DISPLAY INVISIBLE (-5600 800);
FORCEPROP 1 LAST BODY_TYPE PLUMBING
J 0
(-5600 750);
DISPLAY 1.595745 (-5600 750);
PAINT GREEN (-5600 750);
DISPLAY INVISIBLE (-5600 750);
FORCEPROP 1 LAST HDL_TAP TRUE
J 0
(-5275 675);
DISPLAY 1.595745 (-5275 675);
PAINT GREEN (-5275 675);
DISPLAY INVISIBLE (-5275 675);
FORCEPROP 1 LAST PATH I10
J 0
(-5602 800);
DISPLAY 0.872340 (-5602 800);
PAINT GREEN (-5602 800);
DISPLAY INVISIBLE (-5602 800);
FORCEADD TAP..6
R 2
(-2875 1550);
FORCEPROP 3 LASTPIN (-2925 1550) SIG_NAME M_M_ODT<3>
J 0
(-2915 1560);
DISPLAY 0.659574 (-2915 1560);
PAINT MONO (-2915 1560);
DISPLAY INVISIBLE (-2915 1560);
FORCEPROP 1 LASTPIN (-2925 1550) BN 3
J 2
(-2873 1558);
DISPLAY 0.617021 (-2873 1558);
PAINT GREEN (-2873 1558);
FORCEPROP 2 LAST CDS_LIB mstr_standard
J 0
(-2875 1550);
PAINT MONO (-2875 1550);
DISPLAY INVISIBLE (-2875 1550);
FORCEPROP 1 LAST BODY_TYPE PLUMBING
J 2
(-2875 1500);
DISPLAY 1.595745 (-2875 1500);
PAINT GREEN (-2875 1500);
DISPLAY INVISIBLE (-2875 1500);
FORCEPROP 1 LAST HDL_TAP TRUE
J 2
(-3200 1425);
DISPLAY 1.595745 (-3200 1425);
PAINT GREEN (-3200 1425);
DISPLAY INVISIBLE (-3200 1425);
FORCEPROP 1 LAST PATH I100
J 2
(-2873 1550);
DISPLAY 0.872340 (-2873 1550);
PAINT GREEN (-2873 1550);
DISPLAY INVISIBLE (-2873 1550);
FORCEADD TAP..6
R 2
(-2875 1500);
FORCEPROP 3 LASTPIN (-2925 1500) SIG_NAME M_M_ODT<2>
J 0
(-2915 1510);
DISPLAY 0.659574 (-2915 1510);
PAINT MONO (-2915 1510);
DISPLAY INVISIBLE (-2915 1510);
FORCEPROP 1 LASTPIN (-2925 1500) BN 2
J 2
(-2873 1508);
DISPLAY 0.617021 (-2873 1508);
PAINT GREEN (-2873 1508);
FORCEPROP 2 LAST CDS_LIB mstr_standard
J 0
(-2875 1500);
PAINT MONO (-2875 1500);
DISPLAY INVISIBLE (-2875 1500);
FORCEPROP 1 LAST BODY_TYPE PLUMBING
J 2
(-2875 1450);
DISPLAY 1.595745 (-2875 1450);
PAINT GREEN (-2875 1450);
DISPLAY INVISIBLE (-2875 1450);
FORCEPROP 1 LAST HDL_TAP TRUE
J 2
(-3200 1375);
DISPLAY 1.595745 (-3200 1375);
PAINT GREEN (-3200 1375);
DISPLAY INVISIBLE (-3200 1375);
FORCEPROP 1 LAST PATH I101
J 2
(-2873 1500);
DISPLAY 0.872340 (-2873 1500);
PAINT GREEN (-2873 1500);
DISPLAY INVISIBLE (-2873 1500);
FORCEADD TAP..6
R 2
(-2875 1450);
FORCEPROP 3 LASTPIN (-2925 1450) SIG_NAME M_M_ODT<1>
J 0
(-2915 1460);
DISPLAY 0.659574 (-2915 1460);
PAINT MONO (-2915 1460);
DISPLAY INVISIBLE (-2915 1460);
FORCEPROP 1 LASTPIN (-2925 1450) BN 1
J 2
(-2873 1458);
DISPLAY 0.617021 (-2873 1458);
PAINT GREEN (-2873 1458);
FORCEPROP 2 LAST CDS_LIB mstr_standard
J 0
(-2875 1450);
PAINT MONO (-2875 1450);
DISPLAY INVISIBLE (-2875 1450);
FORCEPROP 1 LAST BODY_TYPE PLUMBING
J 2
(-2875 1400);
DISPLAY 1.595745 (-2875 1400);
PAINT GREEN (-2875 1400);
DISPLAY INVISIBLE (-2875 1400);
FORCEPROP 1 LAST HDL_TAP TRUE
J 2
(-3200 1325);
DISPLAY 1.595745 (-3200 1325);
PAINT GREEN (-3200 1325);
DISPLAY INVISIBLE (-3200 1325);
FORCEPROP 1 LAST PATH I102
J 2
(-2873 1450);
DISPLAY 0.872340 (-2873 1450);
PAINT GREEN (-2873 1450);
DISPLAY INVISIBLE (-2873 1450);
FORCEADD TAP..6
R 2
(-2875 1650);
FORCEPROP 3 LASTPIN (-2925 1650) SIG_NAME M_M_CKE<0>
J 0
(-2915 1660);
DISPLAY 0.659574 (-2915 1660);
PAINT MONO (-2915 1660);
DISPLAY INVISIBLE (-2915 1660);
FORCEPROP 1 LASTPIN (-2925 1650) BN 0
J 2
(-2873 1658);
DISPLAY 0.617021 (-2873 1658);
PAINT GREEN (-2873 1658);
FORCEPROP 2 LAST CDS_LIB mstr_standard
J 0
(-2875 1650);
PAINT MONO (-2875 1650);
DISPLAY INVISIBLE (-2875 1650);
FORCEPROP 1 LAST BODY_TYPE PLUMBING
J 2
(-2875 1600);
DISPLAY 1.595745 (-2875 1600);
PAINT GREEN (-2875 1600);
DISPLAY INVISIBLE (-2875 1600);
FORCEPROP 1 LAST HDL_TAP TRUE
J 2
(-3200 1525);
DISPLAY 1.595745 (-3200 1525);
PAINT GREEN (-3200 1525);
DISPLAY INVISIBLE (-3200 1525);
FORCEPROP 1 LAST PATH I103
J 2
(-2873 1650);
DISPLAY 0.872340 (-2873 1650);
PAINT GREEN (-2873 1650);
DISPLAY INVISIBLE (-2873 1650);
FORCEADD TAP..6
R 2
(-2875 1700);
FORCEPROP 3 LASTPIN (-2925 1700) SIG_NAME M_M_CKE<1>
J 0
(-2915 1710);
DISPLAY 0.659574 (-2915 1710);
PAINT MONO (-2915 1710);
DISPLAY INVISIBLE (-2915 1710);
FORCEPROP 1 LASTPIN (-2925 1700) BN 1
J 2
(-2873 1708);
DISPLAY 0.617021 (-2873 1708);
PAINT GREEN (-2873 1708);
FORCEPROP 2 LAST CDS_LIB mstr_standard
J 0
(-2875 1700);
PAINT MONO (-2875 1700);
DISPLAY INVISIBLE (-2875 1700);
FORCEPROP 1 LAST BODY_TYPE PLUMBING
J 2
(-2875 1650);
DISPLAY 1.595745 (-2875 1650);
PAINT GREEN (-2875 1650);
DISPLAY INVISIBLE (-2875 1650);
FORCEPROP 1 LAST HDL_TAP TRUE
J 2
(-3200 1575);
DISPLAY 1.595745 (-3200 1575);
PAINT GREEN (-3200 1575);
DISPLAY INVISIBLE (-3200 1575);
FORCEPROP 1 LAST PATH I104
J 2
(-2873 1700);
DISPLAY 0.872340 (-2873 1700);
PAINT GREEN (-2873 1700);
DISPLAY INVISIBLE (-2873 1700);
FORCEADD TAP..6
R 2
(-2875 1750);
FORCEPROP 3 LASTPIN (-2925 1750) SIG_NAME M_M_CKE<2>
J 0
(-2915 1760);
DISPLAY 0.659574 (-2915 1760);
PAINT MONO (-2915 1760);
DISPLAY INVISIBLE (-2915 1760);
FORCEPROP 1 LASTPIN (-2925 1750) BN 2
J 2
(-2873 1758);
DISPLAY 0.617021 (-2873 1758);
PAINT GREEN (-2873 1758);
FORCEPROP 2 LAST CDS_LIB mstr_standard
J 0
(-2875 1750);
PAINT MONO (-2875 1750);
DISPLAY INVISIBLE (-2875 1750);
FORCEPROP 1 LAST BODY_TYPE PLUMBING
J 2
(-2875 1700);
DISPLAY 1.595745 (-2875 1700);
PAINT GREEN (-2875 1700);
DISPLAY INVISIBLE (-2875 1700);
FORCEPROP 1 LAST HDL_TAP TRUE
J 2
(-3200 1625);
DISPLAY 1.595745 (-3200 1625);
PAINT GREEN (-3200 1625);
DISPLAY INVISIBLE (-3200 1625);
FORCEPROP 1 LAST PATH I105
J 2
(-2873 1750);
DISPLAY 0.872340 (-2873 1750);
PAINT GREEN (-2873 1750);
DISPLAY INVISIBLE (-2873 1750);
FORCEADD TAP..6
R 2
(-2875 1800);
FORCEPROP 3 LASTPIN (-2925 1800) SIG_NAME M_M_CKE<3>
J 0
(-2915 1810);
DISPLAY 0.659574 (-2915 1810);
PAINT MONO (-2915 1810);
DISPLAY INVISIBLE (-2915 1810);
FORCEPROP 1 LASTPIN (-2925 1800) BN 3
J 2
(-2873 1808);
DISPLAY 0.617021 (-2873 1808);
PAINT GREEN (-2873 1808);
FORCEPROP 2 LAST CDS_LIB mstr_standard
J 0
(-2875 1800);
PAINT MONO (-2875 1800);
DISPLAY INVISIBLE (-2875 1800);
FORCEPROP 1 LAST BODY_TYPE PLUMBING
J 2
(-2875 1750);
DISPLAY 1.595745 (-2875 1750);
PAINT GREEN (-2875 1750);
DISPLAY INVISIBLE (-2875 1750);
FORCEPROP 1 LAST HDL_TAP TRUE
J 2
(-3200 1675);
DISPLAY 1.595745 (-3200 1675);
PAINT GREEN (-3200 1675);
DISPLAY INVISIBLE (-3200 1675);
FORCEPROP 1 LAST PATH I106
J 2
(-2873 1800);
DISPLAY 0.872340 (-2873 1800);
PAINT GREEN (-2873 1800);
DISPLAY INVISIBLE (-2873 1800);
FORCEADD TAP..6
R 2
(-2875 1900);
FORCEPROP 3 LASTPIN (-2925 1900) SIG_NAME M_M_MA<0>
J 0
(-2915 1910);
DISPLAY 0.659574 (-2915 1910);
PAINT MONO (-2915 1910);
DISPLAY INVISIBLE (-2915 1910);
FORCEPROP 1 LASTPIN (-2925 1900) BN 0
J 2
(-2873 1908);
DISPLAY 0.617021 (-2873 1908);
PAINT GREEN (-2873 1908);
FORCEPROP 2 LAST CDS_LIB mstr_standard
J 0
(-2875 1900);
PAINT MONO (-2875 1900);
DISPLAY INVISIBLE (-2875 1900);
FORCEPROP 1 LAST BODY_TYPE PLUMBING
J 2
(-2875 1850);
DISPLAY 1.595745 (-2875 1850);
PAINT GREEN (-2875 1850);
DISPLAY INVISIBLE (-2875 1850);
FORCEPROP 1 LAST HDL_TAP TRUE
J 2
(-3200 1775);
DISPLAY 1.595745 (-3200 1775);
PAINT GREEN (-3200 1775);
DISPLAY INVISIBLE (-3200 1775);
FORCEPROP 1 LAST PATH I107
J 2
(-2873 1900);
DISPLAY 0.872340 (-2873 1900);
PAINT GREEN (-2873 1900);
DISPLAY INVISIBLE (-2873 1900);
FORCEADD TAP..6
R 2
(-2875 1950);
FORCEPROP 3 LASTPIN (-2925 1950) SIG_NAME M_M_MA<1>
J 0
(-2915 1960);
DISPLAY 0.659574 (-2915 1960);
PAINT MONO (-2915 1960);
DISPLAY INVISIBLE (-2915 1960);
FORCEPROP 1 LASTPIN (-2925 1950) BN 1
J 2
(-2873 1958);
DISPLAY 0.617021 (-2873 1958);
PAINT GREEN (-2873 1958);
FORCEPROP 2 LAST CDS_LIB mstr_standard
J 0
(-2875 1950);
PAINT MONO (-2875 1950);
DISPLAY INVISIBLE (-2875 1950);
FORCEPROP 1 LAST BODY_TYPE PLUMBING
J 2
(-2875 1900);
DISPLAY 1.595745 (-2875 1900);
PAINT GREEN (-2875 1900);
DISPLAY INVISIBLE (-2875 1900);
FORCEPROP 1 LAST HDL_TAP TRUE
J 2
(-3200 1825);
DISPLAY 1.595745 (-3200 1825);
PAINT GREEN (-3200 1825);
DISPLAY INVISIBLE (-3200 1825);
FORCEPROP 1 LAST PATH I108
J 2
(-2873 1950);
DISPLAY 0.872340 (-2873 1950);
PAINT GREEN (-2873 1950);
DISPLAY INVISIBLE (-2873 1950);
FORCEADD TAP..6
R 2
(-2875 2050);
FORCEPROP 3 LASTPIN (-2925 2050) SIG_NAME M_M_MA<3>
J 0
(-2915 2060);
DISPLAY 0.659574 (-2915 2060);
PAINT MONO (-2915 2060);
DISPLAY INVISIBLE (-2915 2060);
FORCEPROP 1 LASTPIN (-2925 2050) BN 3
J 2
(-2873 2058);
DISPLAY 0.617021 (-2873 2058);
PAINT GREEN (-2873 2058);
FORCEPROP 2 LAST CDS_LIB mstr_standard
J 0
(-2875 2050);
PAINT MONO (-2875 2050);
DISPLAY INVISIBLE (-2875 2050);
FORCEPROP 1 LAST BODY_TYPE PLUMBING
J 2
(-2875 2000);
DISPLAY 1.595745 (-2875 2000);
PAINT GREEN (-2875 2000);
DISPLAY INVISIBLE (-2875 2000);
FORCEPROP 1 LAST HDL_TAP TRUE
J 2
(-3200 1925);
DISPLAY 1.595745 (-3200 1925);
PAINT GREEN (-3200 1925);
DISPLAY INVISIBLE (-3200 1925);
FORCEPROP 1 LAST PATH I109
J 2
(-2873 2050);
DISPLAY 0.872340 (-2873 2050);
PAINT GREEN (-2873 2050);
DISPLAY INVISIBLE (-2873 2050);
FORCEADD TAP..6
(-5600 900);
FORCEPROP 3 LASTPIN (-5550 900) SIG_NAME M_M_CLK_DP<2>
J 0
(-5540 910);
DISPLAY 0.659574 (-5540 910);
PAINT MONO (-5540 910);
DISPLAY INVISIBLE (-5540 910);
FORCEPROP 1 LASTPIN (-5550 900) BN 2
J 0
(-5602 908);
DISPLAY 0.617021 (-5602 908);
PAINT GREEN (-5602 908);
FORCEPROP 2 LAST CDS_LIB mstr_standard
J 0
(-5600 900);
PAINT MONO (-5600 900);
DISPLAY INVISIBLE (-5600 900);
FORCEPROP 1 LAST BODY_TYPE PLUMBING
J 0
(-5600 850);
DISPLAY 1.595745 (-5600 850);
PAINT GREEN (-5600 850);
DISPLAY INVISIBLE (-5600 850);
FORCEPROP 1 LAST HDL_TAP TRUE
J 0
(-5275 775);
DISPLAY 1.595745 (-5275 775);
PAINT GREEN (-5275 775);
DISPLAY INVISIBLE (-5275 775);
FORCEPROP 1 LAST PATH I11
J 0
(-5602 900);
DISPLAY 0.872340 (-5602 900);
PAINT GREEN (-5602 900);
DISPLAY INVISIBLE (-5602 900);
FORCEADD TAP..6
R 2
(-2875 2000);
FORCEPROP 3 LASTPIN (-2925 2000) SIG_NAME M_M_MA<2>
J 0
(-2915 2010);
DISPLAY 0.659574 (-2915 2010);
PAINT MONO (-2915 2010);
DISPLAY INVISIBLE (-2915 2010);
FORCEPROP 1 LASTPIN (-2925 2000) BN 2
J 2
(-2873 2008);
DISPLAY 0.617021 (-2873 2008);
PAINT GREEN (-2873 2008);
FORCEPROP 2 LAST CDS_LIB mstr_standard
J 0
(-2875 2000);
PAINT MONO (-2875 2000);
DISPLAY INVISIBLE (-2875 2000);
FORCEPROP 1 LAST BODY_TYPE PLUMBING
J 2
(-2875 1950);
DISPLAY 1.595745 (-2875 1950);
PAINT GREEN (-2875 1950);
DISPLAY INVISIBLE (-2875 1950);
FORCEPROP 1 LAST HDL_TAP TRUE
J 2
(-3200 1875);
DISPLAY 1.595745 (-3200 1875);
PAINT GREEN (-3200 1875);
DISPLAY INVISIBLE (-3200 1875);
FORCEPROP 1 LAST PATH I110
J 2
(-2873 2000);
DISPLAY 0.872340 (-2873 2000);
PAINT GREEN (-2873 2000);
DISPLAY INVISIBLE (-2873 2000);
FORCEADD TAP..6
R 2
(-2875 2100);
FORCEPROP 3 LASTPIN (-2925 2100) SIG_NAME M_M_MA<4>
J 0
(-2915 2110);
DISPLAY 0.659574 (-2915 2110);
PAINT MONO (-2915 2110);
DISPLAY INVISIBLE (-2915 2110);
FORCEPROP 1 LASTPIN (-2925 2100) BN 4
J 2
(-2873 2108);
DISPLAY 0.617021 (-2873 2108);
PAINT GREEN (-2873 2108);
FORCEPROP 2 LAST CDS_LIB mstr_standard
J 0
(-2875 2100);
PAINT MONO (-2875 2100);
DISPLAY INVISIBLE (-2875 2100);
FORCEPROP 1 LAST BODY_TYPE PLUMBING
J 2
(-2875 2050);
DISPLAY 1.595745 (-2875 2050);
PAINT GREEN (-2875 2050);
DISPLAY INVISIBLE (-2875 2050);
FORCEPROP 1 LAST HDL_TAP TRUE
J 2
(-3200 1975);
DISPLAY 1.595745 (-3200 1975);
PAINT GREEN (-3200 1975);
DISPLAY INVISIBLE (-3200 1975);
FORCEPROP 1 LAST PATH I111
J 2
(-2873 2100);
DISPLAY 0.872340 (-2873 2100);
PAINT GREEN (-2873 2100);
DISPLAY INVISIBLE (-2873 2100);
FORCEADD TAP..6
R 2
(-2875 2150);
FORCEPROP 3 LASTPIN (-2925 2150) SIG_NAME M_M_MA<5>
J 0
(-2915 2160);
DISPLAY 0.659574 (-2915 2160);
PAINT MONO (-2915 2160);
DISPLAY INVISIBLE (-2915 2160);
FORCEPROP 1 LASTPIN (-2925 2150) BN 5
J 2
(-2873 2158);
DISPLAY 0.617021 (-2873 2158);
PAINT GREEN (-2873 2158);
FORCEPROP 2 LAST CDS_LIB mstr_standard
J 0
(-2875 2150);
PAINT MONO (-2875 2150);
DISPLAY INVISIBLE (-2875 2150);
FORCEPROP 1 LAST BODY_TYPE PLUMBING
J 2
(-2875 2100);
DISPLAY 1.595745 (-2875 2100);
PAINT GREEN (-2875 2100);
DISPLAY INVISIBLE (-2875 2100);
FORCEPROP 1 LAST HDL_TAP TRUE
J 2
(-3200 2025);
DISPLAY 1.595745 (-3200 2025);
PAINT GREEN (-3200 2025);
DISPLAY INVISIBLE (-3200 2025);
FORCEPROP 1 LAST PATH I112
J 2
(-2873 2150);
DISPLAY 0.872340 (-2873 2150);
PAINT GREEN (-2873 2150);
DISPLAY INVISIBLE (-2873 2150);
FORCEADD TAP..6
R 2
(-2875 2200);
FORCEPROP 3 LASTPIN (-2925 2200) SIG_NAME M_M_MA<6>
J 0
(-2915 2210);
DISPLAY 0.659574 (-2915 2210);
PAINT MONO (-2915 2210);
DISPLAY INVISIBLE (-2915 2210);
FORCEPROP 1 LASTPIN (-2925 2200) BN 6
J 2
(-2873 2208);
DISPLAY 0.617021 (-2873 2208);
PAINT GREEN (-2873 2208);
FORCEPROP 2 LAST CDS_LIB mstr_standard
J 0
(-2875 2200);
PAINT MONO (-2875 2200);
DISPLAY INVISIBLE (-2875 2200);
FORCEPROP 1 LAST BODY_TYPE PLUMBING
J 2
(-2875 2150);
DISPLAY 1.595745 (-2875 2150);
PAINT GREEN (-2875 2150);
DISPLAY INVISIBLE (-2875 2150);
FORCEPROP 1 LAST HDL_TAP TRUE
J 2
(-3200 2075);
DISPLAY 1.595745 (-3200 2075);
PAINT GREEN (-3200 2075);
DISPLAY INVISIBLE (-3200 2075);
FORCEPROP 1 LAST PATH I113
J 2
(-2873 2200);
DISPLAY 0.872340 (-2873 2200);
PAINT GREEN (-2873 2200);
DISPLAY INVISIBLE (-2873 2200);
FORCEADD TAP..6
R 2
(-2875 2300);
FORCEPROP 3 LASTPIN (-2925 2300) SIG_NAME M_M_MA<8>
J 0
(-2915 2310);
DISPLAY 0.659574 (-2915 2310);
PAINT MONO (-2915 2310);
DISPLAY INVISIBLE (-2915 2310);
FORCEPROP 1 LASTPIN (-2925 2300) BN 8
J 2
(-2873 2308);
DISPLAY 0.617021 (-2873 2308);
PAINT GREEN (-2873 2308);
FORCEPROP 2 LAST CDS_LIB mstr_standard
J 0
(-2875 2300);
PAINT MONO (-2875 2300);
DISPLAY INVISIBLE (-2875 2300);
FORCEPROP 1 LAST BODY_TYPE PLUMBING
J 2
(-2875 2250);
DISPLAY 1.595745 (-2875 2250);
PAINT GREEN (-2875 2250);
DISPLAY INVISIBLE (-2875 2250);
FORCEPROP 1 LAST HDL_TAP TRUE
J 2
(-3200 2175);
DISPLAY 1.595745 (-3200 2175);
PAINT GREEN (-3200 2175);
DISPLAY INVISIBLE (-3200 2175);
FORCEPROP 1 LAST PATH I114
J 2
(-2873 2300);
DISPLAY 0.872340 (-2873 2300);
PAINT GREEN (-2873 2300);
DISPLAY INVISIBLE (-2873 2300);
FORCEADD TAP..6
R 2
(-2875 2250);
FORCEPROP 3 LASTPIN (-2925 2250) SIG_NAME M_M_MA<7>
J 0
(-2915 2260);
DISPLAY 0.659574 (-2915 2260);
PAINT MONO (-2915 2260);
DISPLAY INVISIBLE (-2915 2260);
FORCEPROP 1 LASTPIN (-2925 2250) BN 7
J 2
(-2873 2258);
DISPLAY 0.617021 (-2873 2258);
PAINT GREEN (-2873 2258);
FORCEPROP 2 LAST CDS_LIB mstr_standard
J 0
(-2875 2250);
PAINT MONO (-2875 2250);
DISPLAY INVISIBLE (-2875 2250);
FORCEPROP 1 LAST BODY_TYPE PLUMBING
J 2
(-2875 2200);
DISPLAY 1.595745 (-2875 2200);
PAINT GREEN (-2875 2200);
DISPLAY INVISIBLE (-2875 2200);
FORCEPROP 1 LAST HDL_TAP TRUE
J 2
(-3200 2125);
DISPLAY 1.595745 (-3200 2125);
PAINT GREEN (-3200 2125);
DISPLAY INVISIBLE (-3200 2125);
FORCEPROP 1 LAST PATH I115
J 2
(-2873 2250);
DISPLAY 0.872340 (-2873 2250);
PAINT GREEN (-2873 2250);
DISPLAY INVISIBLE (-2873 2250);
FORCEADD TAP..6
R 2
(-2875 2450);
FORCEPROP 3 LASTPIN (-2925 2450) SIG_NAME M_M_MA<11>
J 0
(-2915 2460);
DISPLAY 0.659574 (-2915 2460);
PAINT MONO (-2915 2460);
DISPLAY INVISIBLE (-2915 2460);
FORCEPROP 1 LASTPIN (-2925 2450) BN 11
J 2
(-2873 2458);
DISPLAY 0.617021 (-2873 2458);
PAINT GREEN (-2873 2458);
FORCEPROP 2 LAST CDS_LIB mstr_standard
J 0
(-2875 2450);
PAINT MONO (-2875 2450);
DISPLAY INVISIBLE (-2875 2450);
FORCEPROP 1 LAST BODY_TYPE PLUMBING
J 2
(-2875 2400);
DISPLAY 1.595745 (-2875 2400);
PAINT GREEN (-2875 2400);
DISPLAY INVISIBLE (-2875 2400);
FORCEPROP 1 LAST HDL_TAP TRUE
J 2
(-3200 2325);
DISPLAY 1.595745 (-3200 2325);
PAINT GREEN (-3200 2325);
DISPLAY INVISIBLE (-3200 2325);
FORCEPROP 1 LAST PATH I116
J 2
(-2873 2450);
DISPLAY 0.872340 (-2873 2450);
PAINT GREEN (-2873 2450);
DISPLAY INVISIBLE (-2873 2450);
FORCEADD TAP..6
R 2
(-2875 2400);
FORCEPROP 3 LASTPIN (-2925 2400) SIG_NAME M_M_MA<10>
J 0
(-2915 2410);
DISPLAY 0.659574 (-2915 2410);
PAINT MONO (-2915 2410);
DISPLAY INVISIBLE (-2915 2410);
FORCEPROP 1 LASTPIN (-2925 2400) BN 10
J 2
(-2873 2408);
DISPLAY 0.617021 (-2873 2408);
PAINT GREEN (-2873 2408);
FORCEPROP 2 LAST CDS_LIB mstr_standard
J 0
(-2875 2400);
PAINT MONO (-2875 2400);
DISPLAY INVISIBLE (-2875 2400);
FORCEPROP 1 LAST BODY_TYPE PLUMBING
J 2
(-2875 2350);
DISPLAY 1.595745 (-2875 2350);
PAINT GREEN (-2875 2350);
DISPLAY INVISIBLE (-2875 2350);
FORCEPROP 1 LAST HDL_TAP TRUE
J 2
(-3200 2275);
DISPLAY 1.595745 (-3200 2275);
PAINT GREEN (-3200 2275);
DISPLAY INVISIBLE (-3200 2275);
FORCEPROP 1 LAST PATH I117
J 2
(-2873 2400);
DISPLAY 0.872340 (-2873 2400);
PAINT GREEN (-2873 2400);
DISPLAY INVISIBLE (-2873 2400);
FORCEADD TAP..6
R 2
(-2875 2350);
FORCEPROP 3 LASTPIN (-2925 2350) SIG_NAME M_M_MA<9>
J 0
(-2915 2360);
DISPLAY 0.659574 (-2915 2360);
PAINT MONO (-2915 2360);
DISPLAY INVISIBLE (-2915 2360);
FORCEPROP 1 LASTPIN (-2925 2350) BN 9
J 2
(-2873 2358);
DISPLAY 0.617021 (-2873 2358);
PAINT GREEN (-2873 2358);
FORCEPROP 2 LAST CDS_LIB mstr_standard
J 0
(-2875 2350);
PAINT MONO (-2875 2350);
DISPLAY INVISIBLE (-2875 2350);
FORCEPROP 1 LAST BODY_TYPE PLUMBING
J 2
(-2875 2300);
DISPLAY 1.595745 (-2875 2300);
PAINT GREEN (-2875 2300);
DISPLAY INVISIBLE (-2875 2300);
FORCEPROP 1 LAST HDL_TAP TRUE
J 2
(-3200 2225);
DISPLAY 1.595745 (-3200 2225);
PAINT GREEN (-3200 2225);
DISPLAY INVISIBLE (-3200 2225);
FORCEPROP 1 LAST PATH I118
J 2
(-2873 2350);
DISPLAY 0.872340 (-2873 2350);
PAINT GREEN (-2873 2350);
DISPLAY INVISIBLE (-2873 2350);
FORCEADD TAP..6
R 2
(-2875 2500);
FORCEPROP 3 LASTPIN (-2925 2500) SIG_NAME M_M_MA<12>
J 0
(-2915 2510);
DISPLAY 0.659574 (-2915 2510);
PAINT MONO (-2915 2510);
DISPLAY INVISIBLE (-2915 2510);
FORCEPROP 1 LASTPIN (-2925 2500) BN 12
J 2
(-2873 2508);
DISPLAY 0.617021 (-2873 2508);
PAINT GREEN (-2873 2508);
FORCEPROP 2 LAST CDS_LIB mstr_standard
J 0
(-2875 2500);
PAINT MONO (-2875 2500);
DISPLAY INVISIBLE (-2875 2500);
FORCEPROP 1 LAST BODY_TYPE PLUMBING
J 2
(-2875 2450);
DISPLAY 1.595745 (-2875 2450);
PAINT GREEN (-2875 2450);
DISPLAY INVISIBLE (-2875 2450);
FORCEPROP 1 LAST HDL_TAP TRUE
J 2
(-3200 2375);
DISPLAY 1.595745 (-3200 2375);
PAINT GREEN (-3200 2375);
DISPLAY INVISIBLE (-3200 2375);
FORCEPROP 1 LAST PATH I119
J 2
(-2873 2500);
DISPLAY 0.872340 (-2873 2500);
PAINT GREEN (-2873 2500);
DISPLAY INVISIBLE (-2873 2500);
FORCEADD TAP..6
(-5600 950);
FORCEPROP 3 LASTPIN (-5550 950) SIG_NAME M_M_CLK_DP<3>
J 0
(-5540 960);
DISPLAY 0.659574 (-5540 960);
PAINT MONO (-5540 960);
DISPLAY INVISIBLE (-5540 960);
FORCEPROP 1 LASTPIN (-5550 950) BN 3
J 0
(-5602 958);
DISPLAY 0.617021 (-5602 958);
PAINT GREEN (-5602 958);
FORCEPROP 2 LAST CDS_LIB mstr_standard
J 0
(-5600 950);
PAINT MONO (-5600 950);
DISPLAY INVISIBLE (-5600 950);
FORCEPROP 1 LAST BODY_TYPE PLUMBING
J 0
(-5600 900);
DISPLAY 1.595745 (-5600 900);
PAINT GREEN (-5600 900);
DISPLAY INVISIBLE (-5600 900);
FORCEPROP 1 LAST HDL_TAP TRUE
J 0
(-5275 825);
DISPLAY 1.595745 (-5275 825);
PAINT GREEN (-5275 825);
DISPLAY INVISIBLE (-5275 825);
FORCEPROP 1 LAST PATH I12
J 0
(-5602 950);
DISPLAY 0.872340 (-5602 950);
PAINT GREEN (-5602 950);
DISPLAY INVISIBLE (-5602 950);
FORCEADD TAP..6
R 2
(-2875 2550);
FORCEPROP 3 LASTPIN (-2925 2550) SIG_NAME M_M_MA<13>
J 0
(-2915 2560);
DISPLAY 0.659574 (-2915 2560);
PAINT MONO (-2915 2560);
DISPLAY INVISIBLE (-2915 2560);
FORCEPROP 1 LASTPIN (-2925 2550) BN 13
J 2
(-2873 2558);
DISPLAY 0.617021 (-2873 2558);
PAINT GREEN (-2873 2558);
FORCEPROP 2 LAST CDS_LIB mstr_standard
J 0
(-2875 2550);
PAINT MONO (-2875 2550);
DISPLAY INVISIBLE (-2875 2550);
FORCEPROP 1 LAST BODY_TYPE PLUMBING
J 2
(-2875 2500);
DISPLAY 1.595745 (-2875 2500);
PAINT GREEN (-2875 2500);
DISPLAY INVISIBLE (-2875 2500);
FORCEPROP 1 LAST HDL_TAP TRUE
J 2
(-3200 2425);
DISPLAY 1.595745 (-3200 2425);
PAINT GREEN (-3200 2425);
DISPLAY INVISIBLE (-3200 2425);
FORCEPROP 1 LAST PATH I120
J 2
(-2873 2550);
DISPLAY 0.872340 (-2873 2550);
PAINT GREEN (-2873 2550);
DISPLAY INVISIBLE (-2873 2550);
FORCEADD TAP..6
R 2
(-2875 2600);
FORCEPROP 3 LASTPIN (-2925 2600) SIG_NAME M_M_MA<14>
J 0
(-2915 2610);
DISPLAY 0.659574 (-2915 2610);
PAINT MONO (-2915 2610);
DISPLAY INVISIBLE (-2915 2610);
FORCEPROP 1 LASTPIN (-2925 2600) BN 14
J 2
(-2873 2608);
DISPLAY 0.617021 (-2873 2608);
PAINT GREEN (-2873 2608);
FORCEPROP 2 LAST CDS_LIB mstr_standard
J 0
(-2875 2600);
PAINT MONO (-2875 2600);
DISPLAY INVISIBLE (-2875 2600);
FORCEPROP 1 LAST BODY_TYPE PLUMBING
J 2
(-2875 2550);
DISPLAY 1.595745 (-2875 2550);
PAINT GREEN (-2875 2550);
DISPLAY INVISIBLE (-2875 2550);
FORCEPROP 1 LAST HDL_TAP TRUE
J 2
(-3200 2475);
DISPLAY 1.595745 (-3200 2475);
PAINT GREEN (-3200 2475);
DISPLAY INVISIBLE (-3200 2475);
FORCEPROP 1 LAST PATH I121
J 2
(-2873 2600);
DISPLAY 0.872340 (-2873 2600);
PAINT GREEN (-2873 2600);
DISPLAY INVISIBLE (-2873 2600);
FORCEADD TAP..6
R 2
(-2875 2650);
FORCEPROP 3 LASTPIN (-2925 2650) SIG_NAME M_M_MA<15>
J 0
(-2915 2660);
DISPLAY 0.659574 (-2915 2660);
PAINT MONO (-2915 2660);
DISPLAY INVISIBLE (-2915 2660);
FORCEPROP 1 LASTPIN (-2925 2650) BN 15
J 2
(-2873 2658);
DISPLAY 0.617021 (-2873 2658);
PAINT GREEN (-2873 2658);
FORCEPROP 2 LAST CDS_LIB mstr_standard
J 0
(-2875 2650);
PAINT MONO (-2875 2650);
DISPLAY INVISIBLE (-2875 2650);
FORCEPROP 1 LAST BODY_TYPE PLUMBING
J 2
(-2875 2600);
DISPLAY 1.595745 (-2875 2600);
PAINT GREEN (-2875 2600);
DISPLAY INVISIBLE (-2875 2600);
FORCEPROP 1 LAST HDL_TAP TRUE
J 2
(-3200 2525);
DISPLAY 1.595745 (-3200 2525);
PAINT GREEN (-3200 2525);
DISPLAY INVISIBLE (-3200 2525);
FORCEPROP 1 LAST PATH I122
J 2
(-2873 2650);
DISPLAY 0.872340 (-2873 2650);
PAINT GREEN (-2873 2650);
DISPLAY INVISIBLE (-2873 2650);
FORCEADD TAP..6
R 2
(-2875 2700);
FORCEPROP 3 LASTPIN (-2925 2700) SIG_NAME M_M_MA<16>
J 0
(-2915 2710);
DISPLAY 0.659574 (-2915 2710);
PAINT MONO (-2915 2710);
DISPLAY INVISIBLE (-2915 2710);
FORCEPROP 1 LASTPIN (-2925 2700) BN 16
J 2
(-2873 2708);
DISPLAY 0.617021 (-2873 2708);
PAINT GREEN (-2873 2708);
FORCEPROP 2 LAST CDS_LIB mstr_standard
J 0
(-2875 2700);
PAINT MONO (-2875 2700);
DISPLAY INVISIBLE (-2875 2700);
FORCEPROP 1 LAST BODY_TYPE PLUMBING
J 2
(-2875 2650);
DISPLAY 1.595745 (-2875 2650);
PAINT GREEN (-2875 2650);
DISPLAY INVISIBLE (-2875 2650);
FORCEPROP 1 LAST HDL_TAP TRUE
J 2
(-3200 2575);
DISPLAY 1.595745 (-3200 2575);
PAINT GREEN (-3200 2575);
DISPLAY INVISIBLE (-3200 2575);
FORCEPROP 1 LAST PATH I123
J 2
(-2873 2700);
DISPLAY 0.872340 (-2873 2700);
PAINT GREEN (-2873 2700);
DISPLAY INVISIBLE (-2873 2700);
FORCEADD TAP..6
R 2
(-2875 2750);
FORCEPROP 3 LASTPIN (-2925 2750) SIG_NAME M_M_MA<17>
J 0
(-2915 2760);
DISPLAY 0.659574 (-2915 2760);
PAINT MONO (-2915 2760);
DISPLAY INVISIBLE (-2915 2760);
FORCEPROP 1 LASTPIN (-2925 2750) BN 17
J 2
(-2873 2758);
DISPLAY 0.617021 (-2873 2758);
PAINT GREEN (-2873 2758);
FORCEPROP 2 LAST CDS_LIB mstr_standard
J 0
(-2875 2750);
PAINT MONO (-2875 2750);
DISPLAY INVISIBLE (-2875 2750);
FORCEPROP 1 LAST BODY_TYPE PLUMBING
J 2
(-2875 2700);
DISPLAY 1.595745 (-2875 2700);
PAINT GREEN (-2875 2700);
DISPLAY INVISIBLE (-2875 2700);
FORCEPROP 1 LAST HDL_TAP TRUE
J 2
(-3200 2625);
DISPLAY 1.595745 (-3200 2625);
PAINT GREEN (-3200 2625);
DISPLAY INVISIBLE (-3200 2625);
FORCEPROP 1 LAST PATH I124
J 2
(-2873 2750);
DISPLAY 0.872340 (-2873 2750);
PAINT GREEN (-2873 2750);
DISPLAY INVISIBLE (-2873 2750);
FORCEADD TAP..6
R 2
(-2875 2900);
FORCEPROP 3 LASTPIN (-2925 2900) SIG_NAME M_M_DQS_DN<1>
J 0
(-2915 2910);
DISPLAY 0.659574 (-2915 2910);
PAINT MONO (-2915 2910);
DISPLAY INVISIBLE (-2915 2910);
FORCEPROP 1 LASTPIN (-2925 2900) BN 1
J 2
(-2873 2908);
DISPLAY 0.617021 (-2873 2908);
PAINT GREEN (-2873 2908);
FORCEPROP 2 LAST CDS_LIB mstr_standard
J 0
(-2875 2900);
PAINT MONO (-2875 2900);
DISPLAY INVISIBLE (-2875 2900);
FORCEPROP 1 LAST BODY_TYPE PLUMBING
J 2
(-2875 2850);
DISPLAY 1.595745 (-2875 2850);
PAINT GREEN (-2875 2850);
DISPLAY INVISIBLE (-2875 2850);
FORCEPROP 1 LAST HDL_TAP TRUE
J 2
(-3200 2775);
DISPLAY 1.595745 (-3200 2775);
PAINT GREEN (-3200 2775);
DISPLAY INVISIBLE (-3200 2775);
FORCEPROP 1 LAST PATH I125
J 2
(-2873 2900);
DISPLAY 0.872340 (-2873 2900);
PAINT GREEN (-2873 2900);
DISPLAY INVISIBLE (-2873 2900);
FORCEADD TAP..6
R 2
(-2875 2950);
FORCEPROP 3 LASTPIN (-2925 2950) SIG_NAME M_M_DQS_DN<2>
J 0
(-2915 2960);
DISPLAY 0.659574 (-2915 2960);
PAINT MONO (-2915 2960);
DISPLAY INVISIBLE (-2915 2960);
FORCEPROP 1 LASTPIN (-2925 2950) BN 2
J 2
(-2873 2958);
DISPLAY 0.617021 (-2873 2958);
PAINT GREEN (-2873 2958);
FORCEPROP 2 LAST CDS_LIB mstr_standard
J 0
(-2875 2950);
PAINT MONO (-2875 2950);
DISPLAY INVISIBLE (-2875 2950);
FORCEPROP 1 LAST BODY_TYPE PLUMBING
J 2
(-2875 2900);
DISPLAY 1.595745 (-2875 2900);
PAINT GREEN (-2875 2900);
DISPLAY INVISIBLE (-2875 2900);
FORCEPROP 1 LAST HDL_TAP TRUE
J 2
(-3200 2825);
DISPLAY 1.595745 (-3200 2825);
PAINT GREEN (-3200 2825);
DISPLAY INVISIBLE (-3200 2825);
FORCEPROP 1 LAST PATH I126
J 2
(-2873 2950);
DISPLAY 0.872340 (-2873 2950);
PAINT GREEN (-2873 2950);
DISPLAY INVISIBLE (-2873 2950);
FORCEADD TAP..6
R 2
(-2875 2850);
FORCEPROP 3 LASTPIN (-2925 2850) SIG_NAME M_M_DQS_DN<0>
J 0
(-2915 2860);
DISPLAY 0.659574 (-2915 2860);
PAINT MONO (-2915 2860);
DISPLAY INVISIBLE (-2915 2860);
FORCEPROP 1 LASTPIN (-2925 2850) BN 0
J 2
(-2873 2858);
DISPLAY 0.617021 (-2873 2858);
PAINT GREEN (-2873 2858);
FORCEPROP 2 LAST CDS_LIB mstr_standard
J 0
(-2875 2850);
PAINT MONO (-2875 2850);
DISPLAY INVISIBLE (-2875 2850);
FORCEPROP 1 LAST BODY_TYPE PLUMBING
J 2
(-2875 2800);
DISPLAY 1.595745 (-2875 2800);
PAINT GREEN (-2875 2800);
DISPLAY INVISIBLE (-2875 2800);
FORCEPROP 1 LAST HDL_TAP TRUE
J 2
(-3200 2725);
DISPLAY 1.595745 (-3200 2725);
PAINT GREEN (-3200 2725);
DISPLAY INVISIBLE (-3200 2725);
FORCEPROP 1 LAST PATH I127
J 2
(-2873 2850);
DISPLAY 0.872340 (-2873 2850);
PAINT GREEN (-2873 2850);
DISPLAY INVISIBLE (-2873 2850);
FORCEADD TAP..6
R 2
(-2875 3050);
FORCEPROP 3 LASTPIN (-2925 3050) SIG_NAME M_M_DQS_DN<4>
J 0
(-2915 3060);
DISPLAY 0.659574 (-2915 3060);
PAINT MONO (-2915 3060);
DISPLAY INVISIBLE (-2915 3060);
FORCEPROP 1 LASTPIN (-2925 3050) BN 4
J 2
(-2873 3058);
DISPLAY 0.617021 (-2873 3058);
PAINT GREEN (-2873 3058);
FORCEPROP 2 LAST CDS_LIB mstr_standard
J 0
(-2875 3050);
PAINT MONO (-2875 3050);
DISPLAY INVISIBLE (-2875 3050);
FORCEPROP 1 LAST BODY_TYPE PLUMBING
J 2
(-2875 3000);
DISPLAY 1.595745 (-2875 3000);
PAINT GREEN (-2875 3000);
DISPLAY INVISIBLE (-2875 3000);
FORCEPROP 1 LAST HDL_TAP TRUE
J 2
(-3200 2925);
DISPLAY 1.595745 (-3200 2925);
PAINT GREEN (-3200 2925);
DISPLAY INVISIBLE (-3200 2925);
FORCEPROP 1 LAST PATH I128
J 2
(-2873 3050);
DISPLAY 0.872340 (-2873 3050);
PAINT GREEN (-2873 3050);
DISPLAY INVISIBLE (-2873 3050);
FORCEADD TAP..6
R 2
(-2875 3000);
FORCEPROP 3 LASTPIN (-2925 3000) SIG_NAME M_M_DQS_DN<3>
J 0
(-2915 3010);
DISPLAY 0.659574 (-2915 3010);
PAINT MONO (-2915 3010);
DISPLAY INVISIBLE (-2915 3010);
FORCEPROP 1 LASTPIN (-2925 3000) BN 3
J 2
(-2873 3008);
DISPLAY 0.617021 (-2873 3008);
PAINT GREEN (-2873 3008);
FORCEPROP 2 LAST CDS_LIB mstr_standard
J 0
(-2875 3000);
PAINT MONO (-2875 3000);
DISPLAY INVISIBLE (-2875 3000);
FORCEPROP 1 LAST BODY_TYPE PLUMBING
J 2
(-2875 2950);
DISPLAY 1.595745 (-2875 2950);
PAINT GREEN (-2875 2950);
DISPLAY INVISIBLE (-2875 2950);
FORCEPROP 1 LAST HDL_TAP TRUE
J 2
(-3200 2875);
DISPLAY 1.595745 (-3200 2875);
PAINT GREEN (-3200 2875);
DISPLAY INVISIBLE (-3200 2875);
FORCEPROP 1 LAST PATH I129
J 2
(-2873 3000);
DISPLAY 0.872340 (-2873 3000);
PAINT GREEN (-2873 3000);
DISPLAY INVISIBLE (-2873 3000);
FORCEADD TAP..6
(-5600 1050);
FORCEPROP 3 LASTPIN (-5550 1050) SIG_NAME M_M_ECC<0>
J 0
(-5540 1060);
DISPLAY 0.659574 (-5540 1060);
PAINT MONO (-5540 1060);
DISPLAY INVISIBLE (-5540 1060);
FORCEPROP 1 LASTPIN (-5550 1050) BN 0
J 0
(-5602 1058);
DISPLAY 0.617021 (-5602 1058);
PAINT GREEN (-5602 1058);
FORCEPROP 2 LAST CDS_LIB mstr_standard
J 0
(-5600 1050);
PAINT MONO (-5600 1050);
DISPLAY INVISIBLE (-5600 1050);
FORCEPROP 1 LAST BODY_TYPE PLUMBING
J 0
(-5600 1000);
DISPLAY 1.595745 (-5600 1000);
PAINT GREEN (-5600 1000);
DISPLAY INVISIBLE (-5600 1000);
FORCEPROP 1 LAST HDL_TAP TRUE
J 0
(-5275 925);
DISPLAY 1.595745 (-5275 925);
PAINT GREEN (-5275 925);
DISPLAY INVISIBLE (-5275 925);
FORCEPROP 1 LAST PATH I13
J 0
(-5602 1050);
DISPLAY 0.872340 (-5602 1050);
PAINT GREEN (-5602 1050);
DISPLAY INVISIBLE (-5602 1050);
FORCEADD TAP..6
R 2
(-2875 3100);
FORCEPROP 3 LASTPIN (-2925 3100) SIG_NAME M_M_DQS_DN<5>
J 0
(-2915 3110);
DISPLAY 0.659574 (-2915 3110);
PAINT MONO (-2915 3110);
DISPLAY INVISIBLE (-2915 3110);
FORCEPROP 1 LASTPIN (-2925 3100) BN 5
J 2
(-2873 3108);
DISPLAY 0.617021 (-2873 3108);
PAINT GREEN (-2873 3108);
FORCEPROP 2 LAST CDS_LIB mstr_standard
J 0
(-2875 3100);
PAINT MONO (-2875 3100);
DISPLAY INVISIBLE (-2875 3100);
FORCEPROP 1 LAST BODY_TYPE PLUMBING
J 2
(-2875 3050);
DISPLAY 1.595745 (-2875 3050);
PAINT GREEN (-2875 3050);
DISPLAY INVISIBLE (-2875 3050);
FORCEPROP 1 LAST HDL_TAP TRUE
J 2
(-3200 2975);
DISPLAY 1.595745 (-3200 2975);
PAINT GREEN (-3200 2975);
DISPLAY INVISIBLE (-3200 2975);
FORCEPROP 1 LAST PATH I130
J 2
(-2873 3100);
DISPLAY 0.872340 (-2873 3100);
PAINT GREEN (-2873 3100);
DISPLAY INVISIBLE (-2873 3100);
FORCEADD TAP..6
R 2
(-2875 3150);
FORCEPROP 3 LASTPIN (-2925 3150) SIG_NAME M_M_DQS_DN<6>
J 0
(-2915 3160);
DISPLAY 0.659574 (-2915 3160);
PAINT MONO (-2915 3160);
DISPLAY INVISIBLE (-2915 3160);
FORCEPROP 1 LASTPIN (-2925 3150) BN 6
J 2
(-2873 3158);
DISPLAY 0.617021 (-2873 3158);
PAINT GREEN (-2873 3158);
FORCEPROP 2 LAST CDS_LIB mstr_standard
J 0
(-2875 3150);
PAINT MONO (-2875 3150);
DISPLAY INVISIBLE (-2875 3150);
FORCEPROP 1 LAST BODY_TYPE PLUMBING
J 2
(-2875 3100);
DISPLAY 1.595745 (-2875 3100);
PAINT GREEN (-2875 3100);
DISPLAY INVISIBLE (-2875 3100);
FORCEPROP 1 LAST HDL_TAP TRUE
J 2
(-3200 3025);
DISPLAY 1.595745 (-3200 3025);
PAINT GREEN (-3200 3025);
DISPLAY INVISIBLE (-3200 3025);
FORCEPROP 1 LAST PATH I131
J 2
(-2873 3150);
DISPLAY 0.872340 (-2873 3150);
PAINT GREEN (-2873 3150);
DISPLAY INVISIBLE (-2873 3150);
FORCEADD TAP..6
R 2
(-2875 3200);
FORCEPROP 3 LASTPIN (-2925 3200) SIG_NAME M_M_DQS_DN<7>
J 0
(-2915 3210);
DISPLAY 0.659574 (-2915 3210);
PAINT MONO (-2915 3210);
DISPLAY INVISIBLE (-2915 3210);
FORCEPROP 1 LASTPIN (-2925 3200) BN 7
J 2
(-2873 3208);
DISPLAY 0.617021 (-2873 3208);
PAINT GREEN (-2873 3208);
FORCEPROP 2 LAST CDS_LIB mstr_standard
J 0
(-2875 3200);
PAINT MONO (-2875 3200);
DISPLAY INVISIBLE (-2875 3200);
FORCEPROP 1 LAST BODY_TYPE PLUMBING
J 2
(-2875 3150);
DISPLAY 1.595745 (-2875 3150);
PAINT GREEN (-2875 3150);
DISPLAY INVISIBLE (-2875 3150);
FORCEPROP 1 LAST HDL_TAP TRUE
J 2
(-3200 3075);
DISPLAY 1.595745 (-3200 3075);
PAINT GREEN (-3200 3075);
DISPLAY INVISIBLE (-3200 3075);
FORCEPROP 1 LAST PATH I132
J 2
(-2873 3200);
DISPLAY 0.872340 (-2873 3200);
PAINT GREEN (-2873 3200);
DISPLAY INVISIBLE (-2873 3200);
FORCEADD TAP..6
R 2
(-2875 3250);
FORCEPROP 3 LASTPIN (-2925 3250) SIG_NAME M_M_DQS_DN<8>
J 0
(-2915 3260);
DISPLAY 0.659574 (-2915 3260);
PAINT MONO (-2915 3260);
DISPLAY INVISIBLE (-2915 3260);
FORCEPROP 1 LASTPIN (-2925 3250) BN 8
J 2
(-2873 3258);
DISPLAY 0.617021 (-2873 3258);
PAINT GREEN (-2873 3258);
FORCEPROP 2 LAST CDS_LIB mstr_standard
J 0
(-2875 3250);
PAINT MONO (-2875 3250);
DISPLAY INVISIBLE (-2875 3250);
FORCEPROP 1 LAST BODY_TYPE PLUMBING
J 2
(-2875 3200);
DISPLAY 1.595745 (-2875 3200);
PAINT GREEN (-2875 3200);
DISPLAY INVISIBLE (-2875 3200);
FORCEPROP 1 LAST HDL_TAP TRUE
J 2
(-3200 3125);
DISPLAY 1.595745 (-3200 3125);
PAINT GREEN (-3200 3125);
DISPLAY INVISIBLE (-3200 3125);
FORCEPROP 1 LAST PATH I133
J 2
(-2873 3250);
DISPLAY 0.872340 (-2873 3250);
PAINT GREEN (-2873 3250);
DISPLAY INVISIBLE (-2873 3250);
FORCEADD TAP..6
R 2
(-2875 3300);
FORCEPROP 3 LASTPIN (-2925 3300) SIG_NAME M_M_DQS_DN<9>
J 0
(-2915 3310);
DISPLAY 0.659574 (-2915 3310);
PAINT MONO (-2915 3310);
DISPLAY INVISIBLE (-2915 3310);
FORCEPROP 1 LASTPIN (-2925 3300) BN 9
J 2
(-2873 3308);
DISPLAY 0.617021 (-2873 3308);
PAINT GREEN (-2873 3308);
FORCEPROP 2 LAST CDS_LIB mstr_standard
J 0
(-2875 3300);
PAINT MONO (-2875 3300);
DISPLAY INVISIBLE (-2875 3300);
FORCEPROP 1 LAST BODY_TYPE PLUMBING
J 2
(-2875 3250);
DISPLAY 1.595745 (-2875 3250);
PAINT GREEN (-2875 3250);
DISPLAY INVISIBLE (-2875 3250);
FORCEPROP 1 LAST HDL_TAP TRUE
J 2
(-3200 3175);
DISPLAY 1.595745 (-3200 3175);
PAINT GREEN (-3200 3175);
DISPLAY INVISIBLE (-3200 3175);
FORCEPROP 1 LAST PATH I134
J 2
(-2873 3300);
DISPLAY 0.872340 (-2873 3300);
PAINT GREEN (-2873 3300);
DISPLAY INVISIBLE (-2873 3300);
FORCEADD TAP..6
R 2
(-2875 3350);
FORCEPROP 3 LASTPIN (-2925 3350) SIG_NAME M_M_DQS_DN<10>
J 0
(-2915 3360);
DISPLAY 0.659574 (-2915 3360);
PAINT MONO (-2915 3360);
DISPLAY INVISIBLE (-2915 3360);
FORCEPROP 1 LASTPIN (-2925 3350) BN 10
J 2
(-2873 3358);
DISPLAY 0.617021 (-2873 3358);
PAINT GREEN (-2873 3358);
FORCEPROP 2 LAST CDS_LIB mstr_standard
J 0
(-2875 3350);
PAINT MONO (-2875 3350);
DISPLAY INVISIBLE (-2875 3350);
FORCEPROP 1 LAST BODY_TYPE PLUMBING
J 2
(-2875 3300);
DISPLAY 1.595745 (-2875 3300);
PAINT GREEN (-2875 3300);
DISPLAY INVISIBLE (-2875 3300);
FORCEPROP 1 LAST HDL_TAP TRUE
J 2
(-3200 3225);
DISPLAY 1.595745 (-3200 3225);
PAINT GREEN (-3200 3225);
DISPLAY INVISIBLE (-3200 3225);
FORCEPROP 1 LAST PATH I135
J 2
(-2873 3350);
DISPLAY 0.872340 (-2873 3350);
PAINT GREEN (-2873 3350);
DISPLAY INVISIBLE (-2873 3350);
FORCEADD TAP..6
R 2
(-2875 3450);
FORCEPROP 3 LASTPIN (-2925 3450) SIG_NAME M_M_DQS_DN<12>
J 0
(-2915 3460);
DISPLAY 0.659574 (-2915 3460);
PAINT MONO (-2915 3460);
DISPLAY INVISIBLE (-2915 3460);
FORCEPROP 1 LASTPIN (-2925 3450) BN 12
J 2
(-2873 3458);
DISPLAY 0.617021 (-2873 3458);
PAINT GREEN (-2873 3458);
FORCEPROP 2 LAST CDS_LIB mstr_standard
J 0
(-2875 3450);
PAINT MONO (-2875 3450);
DISPLAY INVISIBLE (-2875 3450);
FORCEPROP 1 LAST BODY_TYPE PLUMBING
J 2
(-2875 3400);
DISPLAY 1.595745 (-2875 3400);
PAINT GREEN (-2875 3400);
DISPLAY INVISIBLE (-2875 3400);
FORCEPROP 1 LAST HDL_TAP TRUE
J 2
(-3200 3325);
DISPLAY 1.595745 (-3200 3325);
PAINT GREEN (-3200 3325);
DISPLAY INVISIBLE (-3200 3325);
FORCEPROP 1 LAST PATH I136
J 2
(-2873 3450);
DISPLAY 0.872340 (-2873 3450);
PAINT GREEN (-2873 3450);
DISPLAY INVISIBLE (-2873 3450);
FORCEADD TAP..6
R 2
(-2875 3400);
FORCEPROP 3 LASTPIN (-2925 3400) SIG_NAME M_M_DQS_DN<11>
J 0
(-2915 3410);
DISPLAY 0.659574 (-2915 3410);
PAINT MONO (-2915 3410);
DISPLAY INVISIBLE (-2915 3410);
FORCEPROP 1 LASTPIN (-2925 3400) BN 11
J 2
(-2873 3408);
DISPLAY 0.617021 (-2873 3408);
PAINT GREEN (-2873 3408);
FORCEPROP 2 LAST CDS_LIB mstr_standard
J 0
(-2875 3400);
PAINT MONO (-2875 3400);
DISPLAY INVISIBLE (-2875 3400);
FORCEPROP 1 LAST BODY_TYPE PLUMBING
J 2
(-2875 3350);
DISPLAY 1.595745 (-2875 3350);
PAINT GREEN (-2875 3350);
DISPLAY INVISIBLE (-2875 3350);
FORCEPROP 1 LAST HDL_TAP TRUE
J 2
(-3200 3275);
DISPLAY 1.595745 (-3200 3275);
PAINT GREEN (-3200 3275);
DISPLAY INVISIBLE (-3200 3275);
FORCEPROP 1 LAST PATH I137
J 2
(-2873 3400);
DISPLAY 0.872340 (-2873 3400);
PAINT GREEN (-2873 3400);
DISPLAY INVISIBLE (-2873 3400);
FORCEADD TAP..6
R 2
(-2875 3600);
FORCEPROP 3 LASTPIN (-2925 3600) SIG_NAME M_M_DQS_DN<15>
J 0
(-2915 3610);
DISPLAY 0.659574 (-2915 3610);
PAINT MONO (-2915 3610);
DISPLAY INVISIBLE (-2915 3610);
FORCEPROP 1 LASTPIN (-2925 3600) BN 15
J 2
(-2873 3608);
DISPLAY 0.617021 (-2873 3608);
PAINT GREEN (-2873 3608);
FORCEPROP 2 LAST CDS_LIB mstr_standard
J 0
(-2875 3600);
PAINT MONO (-2875 3600);
DISPLAY INVISIBLE (-2875 3600);
FORCEPROP 1 LAST BODY_TYPE PLUMBING
J 2
(-2875 3550);
DISPLAY 1.595745 (-2875 3550);
PAINT GREEN (-2875 3550);
DISPLAY INVISIBLE (-2875 3550);
FORCEPROP 1 LAST HDL_TAP TRUE
J 2
(-3200 3475);
DISPLAY 1.595745 (-3200 3475);
PAINT GREEN (-3200 3475);
DISPLAY INVISIBLE (-3200 3475);
FORCEPROP 1 LAST PATH I138
J 2
(-2873 3600);
DISPLAY 0.872340 (-2873 3600);
PAINT GREEN (-2873 3600);
DISPLAY INVISIBLE (-2873 3600);
FORCEADD TAP..6
R 2
(-2875 3550);
FORCEPROP 3 LASTPIN (-2925 3550) SIG_NAME M_M_DQS_DN<14>
J 0
(-2915 3560);
DISPLAY 0.659574 (-2915 3560);
PAINT MONO (-2915 3560);
DISPLAY INVISIBLE (-2915 3560);
FORCEPROP 1 LASTPIN (-2925 3550) BN 14
J 2
(-2873 3558);
DISPLAY 0.617021 (-2873 3558);
PAINT GREEN (-2873 3558);
FORCEPROP 2 LAST CDS_LIB mstr_standard
J 0
(-2875 3550);
PAINT MONO (-2875 3550);
DISPLAY INVISIBLE (-2875 3550);
FORCEPROP 1 LAST BODY_TYPE PLUMBING
J 2
(-2875 3500);
DISPLAY 1.595745 (-2875 3500);
PAINT GREEN (-2875 3500);
DISPLAY INVISIBLE (-2875 3500);
FORCEPROP 1 LAST HDL_TAP TRUE
J 2
(-3200 3425);
DISPLAY 1.595745 (-3200 3425);
PAINT GREEN (-3200 3425);
DISPLAY INVISIBLE (-3200 3425);
FORCEPROP 1 LAST PATH I139
J 2
(-2873 3550);
DISPLAY 0.872340 (-2873 3550);
PAINT GREEN (-2873 3550);
DISPLAY INVISIBLE (-2873 3550);
FORCEADD TAP..6
(-5600 1100);
FORCEPROP 3 LASTPIN (-5550 1100) SIG_NAME M_M_ECC<1>
J 0
(-5540 1110);
DISPLAY 0.659574 (-5540 1110);
PAINT MONO (-5540 1110);
DISPLAY INVISIBLE (-5540 1110);
FORCEPROP 1 LASTPIN (-5550 1100) BN 1
J 0
(-5602 1108);
DISPLAY 0.617021 (-5602 1108);
PAINT GREEN (-5602 1108);
FORCEPROP 2 LAST CDS_LIB mstr_standard
J 0
(-5600 1100);
PAINT MONO (-5600 1100);
DISPLAY INVISIBLE (-5600 1100);
FORCEPROP 1 LAST BODY_TYPE PLUMBING
J 0
(-5600 1050);
DISPLAY 1.595745 (-5600 1050);
PAINT GREEN (-5600 1050);
DISPLAY INVISIBLE (-5600 1050);
FORCEPROP 1 LAST HDL_TAP TRUE
J 0
(-5275 975);
DISPLAY 1.595745 (-5275 975);
PAINT GREEN (-5275 975);
DISPLAY INVISIBLE (-5275 975);
FORCEPROP 1 LAST PATH I14
J 0
(-5602 1100);
DISPLAY 0.872340 (-5602 1100);
PAINT GREEN (-5602 1100);
DISPLAY INVISIBLE (-5602 1100);
FORCEADD TAP..6
R 2
(-2875 3500);
FORCEPROP 3 LASTPIN (-2925 3500) SIG_NAME M_M_DQS_DN<13>
J 0
(-2915 3510);
DISPLAY 0.659574 (-2915 3510);
PAINT MONO (-2915 3510);
DISPLAY INVISIBLE (-2915 3510);
FORCEPROP 1 LASTPIN (-2925 3500) BN 13
J 2
(-2873 3508);
DISPLAY 0.617021 (-2873 3508);
PAINT GREEN (-2873 3508);
FORCEPROP 2 LAST CDS_LIB mstr_standard
J 0
(-2875 3500);
PAINT MONO (-2875 3500);
DISPLAY INVISIBLE (-2875 3500);
FORCEPROP 1 LAST BODY_TYPE PLUMBING
J 2
(-2875 3450);
DISPLAY 1.595745 (-2875 3450);
PAINT GREEN (-2875 3450);
DISPLAY INVISIBLE (-2875 3450);
FORCEPROP 1 LAST HDL_TAP TRUE
J 2
(-3200 3375);
DISPLAY 1.595745 (-3200 3375);
PAINT GREEN (-3200 3375);
DISPLAY INVISIBLE (-3200 3375);
FORCEPROP 1 LAST PATH I140
J 2
(-2873 3500);
DISPLAY 0.872340 (-2873 3500);
PAINT GREEN (-2873 3500);
DISPLAY INVISIBLE (-2873 3500);
FORCEADD TAP..6
R 2
(-2875 3650);
FORCEPROP 3 LASTPIN (-2925 3650) SIG_NAME M_M_DQS_DN<16>
J 0
(-2915 3660);
DISPLAY 0.659574 (-2915 3660);
PAINT MONO (-2915 3660);
DISPLAY INVISIBLE (-2915 3660);
FORCEPROP 1 LASTPIN (-2925 3650) BN 16
J 2
(-2873 3658);
DISPLAY 0.617021 (-2873 3658);
PAINT GREEN (-2873 3658);
FORCEPROP 2 LAST CDS_LIB mstr_standard
J 0
(-2875 3650);
PAINT MONO (-2875 3650);
DISPLAY INVISIBLE (-2875 3650);
FORCEPROP 1 LAST BODY_TYPE PLUMBING
J 2
(-2875 3600);
DISPLAY 1.595745 (-2875 3600);
PAINT GREEN (-2875 3600);
DISPLAY INVISIBLE (-2875 3600);
FORCEPROP 1 LAST HDL_TAP TRUE
J 2
(-3200 3525);
DISPLAY 1.595745 (-3200 3525);
PAINT GREEN (-3200 3525);
DISPLAY INVISIBLE (-3200 3525);
FORCEPROP 1 LAST PATH I141
J 2
(-2873 3650);
DISPLAY 0.872340 (-2873 3650);
PAINT GREEN (-2873 3650);
DISPLAY INVISIBLE (-2873 3650);
FORCEADD TAP..6
R 2
(-2875 3700);
FORCEPROP 3 LASTPIN (-2925 3700) SIG_NAME M_M_DQS_DN<17>
J 0
(-2915 3710);
DISPLAY 0.659574 (-2915 3710);
PAINT MONO (-2915 3710);
DISPLAY INVISIBLE (-2915 3710);
FORCEPROP 1 LASTPIN (-2925 3700) BN 17
J 2
(-2873 3708);
DISPLAY 0.617021 (-2873 3708);
PAINT GREEN (-2873 3708);
FORCEPROP 2 LAST CDS_LIB mstr_standard
J 0
(-2875 3700);
PAINT MONO (-2875 3700);
DISPLAY INVISIBLE (-2875 3700);
FORCEPROP 1 LAST BODY_TYPE PLUMBING
J 2
(-2875 3650);
DISPLAY 1.595745 (-2875 3650);
PAINT GREEN (-2875 3650);
DISPLAY INVISIBLE (-2875 3650);
FORCEPROP 1 LAST HDL_TAP TRUE
J 2
(-3200 3575);
DISPLAY 1.595745 (-3200 3575);
PAINT GREEN (-3200 3575);
DISPLAY INVISIBLE (-3200 3575);
FORCEPROP 1 LAST PATH I142
J 2
(-2873 3700);
DISPLAY 0.872340 (-2873 3700);
PAINT GREEN (-2873 3700);
DISPLAY INVISIBLE (-2873 3700);
FORCEADD TAP..6
R 2
(-2875 3800);
FORCEPROP 3 LASTPIN (-2925 3800) SIG_NAME M_M_DQS_DP<0>
J 0
(-2915 3810);
DISPLAY 0.659574 (-2915 3810);
PAINT MONO (-2915 3810);
DISPLAY INVISIBLE (-2915 3810);
FORCEPROP 1 LASTPIN (-2925 3800) BN 0
J 2
(-2873 3808);
DISPLAY 0.617021 (-2873 3808);
PAINT GREEN (-2873 3808);
FORCEPROP 2 LAST CDS_LIB mstr_standard
J 0
(-2875 3800);
PAINT MONO (-2875 3800);
DISPLAY INVISIBLE (-2875 3800);
FORCEPROP 1 LAST BODY_TYPE PLUMBING
J 2
(-2875 3750);
DISPLAY 1.595745 (-2875 3750);
PAINT GREEN (-2875 3750);
DISPLAY INVISIBLE (-2875 3750);
FORCEPROP 1 LAST HDL_TAP TRUE
J 2
(-3200 3675);
DISPLAY 1.595745 (-3200 3675);
PAINT GREEN (-3200 3675);
DISPLAY INVISIBLE (-3200 3675);
FORCEPROP 1 LAST PATH I143
J 2
(-2873 3800);
DISPLAY 0.872340 (-2873 3800);
PAINT GREEN (-2873 3800);
DISPLAY INVISIBLE (-2873 3800);
FORCEADD TAP..6
R 2
(-2875 3850);
FORCEPROP 3 LASTPIN (-2925 3850) SIG_NAME M_M_DQS_DP<1>
J 0
(-2915 3860);
DISPLAY 0.659574 (-2915 3860);
PAINT MONO (-2915 3860);
DISPLAY INVISIBLE (-2915 3860);
FORCEPROP 1 LASTPIN (-2925 3850) BN 1
J 2
(-2873 3858);
DISPLAY 0.617021 (-2873 3858);
PAINT GREEN (-2873 3858);
FORCEPROP 2 LAST CDS_LIB mstr_standard
J 0
(-2875 3850);
PAINT MONO (-2875 3850);
DISPLAY INVISIBLE (-2875 3850);
FORCEPROP 1 LAST BODY_TYPE PLUMBING
J 2
(-2875 3800);
DISPLAY 1.595745 (-2875 3800);
PAINT GREEN (-2875 3800);
DISPLAY INVISIBLE (-2875 3800);
FORCEPROP 1 LAST HDL_TAP TRUE
J 2
(-3200 3725);
DISPLAY 1.595745 (-3200 3725);
PAINT GREEN (-3200 3725);
DISPLAY INVISIBLE (-3200 3725);
FORCEPROP 1 LAST PATH I144
J 2
(-2873 3850);
DISPLAY 0.872340 (-2873 3850);
PAINT GREEN (-2873 3850);
DISPLAY INVISIBLE (-2873 3850);
FORCEADD TAP..6
R 2
(-2875 3900);
FORCEPROP 3 LASTPIN (-2925 3900) SIG_NAME M_M_DQS_DP<2>
J 0
(-2915 3910);
DISPLAY 0.659574 (-2915 3910);
PAINT MONO (-2915 3910);
DISPLAY INVISIBLE (-2915 3910);
FORCEPROP 1 LASTPIN (-2925 3900) BN 2
J 2
(-2873 3908);
DISPLAY 0.617021 (-2873 3908);
PAINT GREEN (-2873 3908);
FORCEPROP 2 LAST CDS_LIB mstr_standard
J 0
(-2875 3900);
PAINT MONO (-2875 3900);
DISPLAY INVISIBLE (-2875 3900);
FORCEPROP 1 LAST BODY_TYPE PLUMBING
J 2
(-2875 3850);
DISPLAY 1.595745 (-2875 3850);
PAINT GREEN (-2875 3850);
DISPLAY INVISIBLE (-2875 3850);
FORCEPROP 1 LAST HDL_TAP TRUE
J 2
(-3200 3775);
DISPLAY 1.595745 (-3200 3775);
PAINT GREEN (-3200 3775);
DISPLAY INVISIBLE (-3200 3775);
FORCEPROP 1 LAST PATH I145
J 2
(-2873 3900);
DISPLAY 0.872340 (-2873 3900);
PAINT GREEN (-2873 3900);
DISPLAY INVISIBLE (-2873 3900);
FORCEADD TAP..6
R 2
(-2875 3950);
FORCEPROP 3 LASTPIN (-2925 3950) SIG_NAME M_M_DQS_DP<3>
J 0
(-2915 3960);
DISPLAY 0.659574 (-2915 3960);
PAINT MONO (-2915 3960);
DISPLAY INVISIBLE (-2915 3960);
FORCEPROP 1 LASTPIN (-2925 3950) BN 3
J 2
(-2873 3958);
DISPLAY 0.617021 (-2873 3958);
PAINT GREEN (-2873 3958);
FORCEPROP 2 LAST CDS_LIB mstr_standard
J 0
(-2875 3950);
PAINT MONO (-2875 3950);
DISPLAY INVISIBLE (-2875 3950);
FORCEPROP 1 LAST BODY_TYPE PLUMBING
J 2
(-2875 3900);
DISPLAY 1.595745 (-2875 3900);
PAINT GREEN (-2875 3900);
DISPLAY INVISIBLE (-2875 3900);
FORCEPROP 1 LAST HDL_TAP TRUE
J 2
(-3200 3825);
DISPLAY 1.595745 (-3200 3825);
PAINT GREEN (-3200 3825);
DISPLAY INVISIBLE (-3200 3825);
FORCEPROP 1 LAST PATH I146
J 2
(-2873 3950);
DISPLAY 0.872340 (-2873 3950);
PAINT GREEN (-2873 3950);
DISPLAY INVISIBLE (-2873 3950);
FORCEADD OFFPAGE..2
(-2025 500);
FORCEPROP 2 LAST $XR0 87 
J 0
(-1836 500);
DISPLAY 0.638298 (-1836 500);
PAINT MONO (-1836 500);
FORCEPROP 2 LAST $XR1 88 
J 0
(-1746 500);
DISPLAY 0.638298 (-1746 500);
PAINT MONO (-1746 500);
FORCEPROP 2 LAST CDS_LIB mstr_standard
J 0
(-2025 500);
PAINT MONO (-2025 500);
DISPLAY INVISIBLE (-2025 500);
FORCEPROP 1 LAST OFFPAGE TRUE
J 0
(-1700 375);
DISPLAY 1.170213 (-1700 375);
PAINT GREEN (-1700 375);
DISPLAY INVISIBLE (-1700 375);
FORCEPROP 1 LAST COMMENT_BODY TRUE
J 0
(-2070 405);
DISPLAY 1.170213 (-2070 405);
PAINT GREEN (-2070 405);
DISPLAY INVISIBLE (-2070 405);
FORCEPROP 2 LAST PATH I147
J 0
(-1850 575);
DISPLAY 1.021277 (-1850 575);
PAINT ORANGE (-1850 575);
DISPLAY INVISIBLE (-1850 575);
FORCEADD OFFPAGE..2
(-2025 600);
FORCEPROP 2 LAST $XR0 87 
J 0
(-1836 600);
DISPLAY 0.638298 (-1836 600);
PAINT MONO (-1836 600);
FORCEPROP 2 LAST $XR1 88 
J 0
(-1746 600);
DISPLAY 0.638298 (-1746 600);
PAINT MONO (-1746 600);
FORCEPROP 2 LAST CDS_LIB mstr_standard
J 0
(-2025 600);
PAINT MONO (-2025 600);
DISPLAY INVISIBLE (-2025 600);
FORCEPROP 1 LAST OFFPAGE TRUE
J 0
(-1700 475);
DISPLAY 1.170213 (-1700 475);
PAINT GREEN (-1700 475);
DISPLAY INVISIBLE (-1700 475);
FORCEPROP 1 LAST COMMENT_BODY TRUE
J 0
(-2070 505);
DISPLAY 1.170213 (-2070 505);
PAINT GREEN (-2070 505);
DISPLAY INVISIBLE (-2070 505);
FORCEPROP 2 LAST PATH I148
J 0
(-1850 675);
DISPLAY 1.021277 (-1850 675);
PAINT ORANGE (-1850 675);
DISPLAY INVISIBLE (-1850 675);
FORCEADD OFFPAGE..4
(-2025 550);
FORCEPROP 2 LAST $XR0 87 
J 0
(-1839 550);
DISPLAY 0.638298 (-1839 550);
PAINT MONO (-1839 550);
FORCEPROP 2 LAST $XR1 88 
J 0
(-1749 550);
DISPLAY 0.638298 (-1749 550);
PAINT MONO (-1749 550);
FORCEPROP 2 LAST CDS_LIB mstr_standard
J 0
(-2025 550);
PAINT MONO (-2025 550);
DISPLAY INVISIBLE (-2025 550);
FORCEPROP 1 LAST OFFPAGE TRUE
J 0
(-1700 425);
DISPLAY 1.170213 (-1700 425);
PAINT GREEN (-1700 425);
DISPLAY INVISIBLE (-1700 425);
FORCEPROP 1 LAST COMMENT_BODY TRUE
J 0
(-2050 450);
DISPLAY 1.170213 (-2050 450);
PAINT GREEN (-2050 450);
DISPLAY INVISIBLE (-2050 450);
FORCEPROP 2 LAST PATH I149
J 0
(-1850 625);
DISPLAY 1.021277 (-1850 625);
PAINT ORANGE (-1850 625);
DISPLAY INVISIBLE (-1850 625);
FORCEADD TAP..6
(-5600 1150);
FORCEPROP 3 LASTPIN (-5550 1150) SIG_NAME M_M_ECC<2>
J 0
(-5540 1160);
DISPLAY 0.659574 (-5540 1160);
PAINT MONO (-5540 1160);
DISPLAY INVISIBLE (-5540 1160);
FORCEPROP 1 LASTPIN (-5550 1150) BN 2
J 0
(-5602 1158);
DISPLAY 0.617021 (-5602 1158);
PAINT GREEN (-5602 1158);
FORCEPROP 2 LAST CDS_LIB mstr_standard
J 0
(-5600 1150);
PAINT MONO (-5600 1150);
DISPLAY INVISIBLE (-5600 1150);
FORCEPROP 1 LAST BODY_TYPE PLUMBING
J 0
(-5600 1100);
DISPLAY 1.595745 (-5600 1100);
PAINT GREEN (-5600 1100);
DISPLAY INVISIBLE (-5600 1100);
FORCEPROP 1 LAST HDL_TAP TRUE
J 0
(-5275 1025);
DISPLAY 1.595745 (-5275 1025);
PAINT GREEN (-5275 1025);
DISPLAY INVISIBLE (-5275 1025);
FORCEPROP 1 LAST PATH I15
J 0
(-5602 1150);
DISPLAY 0.872340 (-5602 1150);
PAINT GREEN (-5602 1150);
DISPLAY INVISIBLE (-5602 1150);
FORCEADD OFFPAGE..2
(-2025 800);
FORCEPROP 2 LAST $XR0 87 
J 0
(-1836 800);
DISPLAY 0.638298 (-1836 800);
PAINT MONO (-1836 800);
FORCEPROP 2 LAST $XR1 88 
J 0
(-1746 800);
DISPLAY 0.638298 (-1746 800);
PAINT MONO (-1746 800);
FORCEPROP 2 LAST CDS_LIB mstr_standard
J 0
(-2025 800);
PAINT MONO (-2025 800);
DISPLAY INVISIBLE (-2025 800);
FORCEPROP 1 LAST OFFPAGE TRUE
J 0
(-1700 675);
DISPLAY 1.170213 (-1700 675);
PAINT GREEN (-1700 675);
DISPLAY INVISIBLE (-1700 675);
FORCEPROP 1 LAST COMMENT_BODY TRUE
J 0
(-2070 705);
DISPLAY 1.170213 (-2070 705);
PAINT GREEN (-2070 705);
DISPLAY INVISIBLE (-2070 705);
FORCEPROP 2 LAST PATH I150
J 0
(-1850 875);
DISPLAY 1.021277 (-1850 875);
PAINT ORANGE (-1850 875);
DISPLAY INVISIBLE (-1850 875);
FORCEADD OFFPAGE..2
(-2025 900);
FORCEPROP 2 LAST $XR0 87 
J 0
(-1836 900);
DISPLAY 0.638298 (-1836 900);
PAINT MONO (-1836 900);
FORCEPROP 2 LAST $XR1 88 
J 0
(-1746 900);
DISPLAY 0.638298 (-1746 900);
PAINT MONO (-1746 900);
FORCEPROP 2 LAST CDS_LIB mstr_standard
J 0
(-2025 900);
PAINT MONO (-2025 900);
DISPLAY INVISIBLE (-2025 900);
FORCEPROP 1 LAST OFFPAGE TRUE
J 0
(-1700 775);
DISPLAY 1.170213 (-1700 775);
PAINT GREEN (-1700 775);
DISPLAY INVISIBLE (-1700 775);
FORCEPROP 1 LAST COMMENT_BODY TRUE
J 0
(-2070 805);
DISPLAY 1.170213 (-2070 805);
PAINT GREEN (-2070 805);
DISPLAY INVISIBLE (-2070 805);
FORCEPROP 2 LAST PATH I151
J 0
(-1850 975);
DISPLAY 1.021277 (-1850 975);
PAINT ORANGE (-1850 975);
DISPLAY INVISIBLE (-1850 975);
FORCEADD OFFPAGE..2
(-2025 1350);
FORCEPROP 2 LAST $XR0 87 
J 0
(-1836 1350);
DISPLAY 0.638298 (-1836 1350);
PAINT MONO (-1836 1350);
FORCEPROP 2 LAST $XR1 88 
J 0
(-1746 1350);
DISPLAY 0.638298 (-1746 1350);
PAINT MONO (-1746 1350);
FORCEPROP 2 LAST CDS_LIB mstr_standard
J 0
(-2025 1350);
PAINT MONO (-2025 1350);
DISPLAY INVISIBLE (-2025 1350);
FORCEPROP 1 LAST OFFPAGE TRUE
J 0
(-1700 1225);
DISPLAY 1.170213 (-1700 1225);
PAINT GREEN (-1700 1225);
DISPLAY INVISIBLE (-1700 1225);
FORCEPROP 1 LAST COMMENT_BODY TRUE
J 0
(-2070 1255);
DISPLAY 1.170213 (-2070 1255);
PAINT GREEN (-2070 1255);
DISPLAY INVISIBLE (-2070 1255);
FORCEPROP 2 LAST PATH I152
J 0
(-1850 1425);
DISPLAY 1.021277 (-1850 1425);
PAINT ORANGE (-1850 1425);
DISPLAY INVISIBLE (-1850 1425);
FORCEADD OFFPAGE..2
(-2025 1600);
FORCEPROP 2 LAST $XR0 87 
J 0
(-1836 1600);
DISPLAY 0.638298 (-1836 1600);
PAINT MONO (-1836 1600);
FORCEPROP 2 LAST $XR1 88 
J 0
(-1746 1600);
DISPLAY 0.638298 (-1746 1600);
PAINT MONO (-1746 1600);
FORCEPROP 2 LAST CDS_LIB mstr_standard
J 0
(-2025 1600);
PAINT MONO (-2025 1600);
DISPLAY INVISIBLE (-2025 1600);
FORCEPROP 1 LAST OFFPAGE TRUE
J 0
(-1700 1475);
DISPLAY 1.170213 (-1700 1475);
PAINT GREEN (-1700 1475);
DISPLAY INVISIBLE (-1700 1475);
FORCEPROP 1 LAST COMMENT_BODY TRUE
J 0
(-2070 1505);
DISPLAY 1.170213 (-2070 1505);
PAINT GREEN (-2070 1505);
DISPLAY INVISIBLE (-2070 1505);
FORCEPROP 2 LAST PATH I153
J 0
(-1850 1675);
DISPLAY 1.021277 (-1850 1675);
PAINT ORANGE (-1850 1675);
DISPLAY INVISIBLE (-1850 1675);
FORCEADD OFFPAGE..2
(-2025 1850);
FORCEPROP 2 LAST $XR0 87 
J 0
(-1836 1850);
DISPLAY 0.638298 (-1836 1850);
PAINT MONO (-1836 1850);
FORCEPROP 2 LAST $XR1 88 
J 0
(-1746 1850);
DISPLAY 0.638298 (-1746 1850);
PAINT MONO (-1746 1850);
FORCEPROP 2 LAST CDS_LIB mstr_standard
J 0
(-2025 1850);
PAINT MONO (-2025 1850);
DISPLAY INVISIBLE (-2025 1850);
FORCEPROP 1 LAST OFFPAGE TRUE
J 0
(-1700 1725);
DISPLAY 1.170213 (-1700 1725);
PAINT GREEN (-1700 1725);
DISPLAY INVISIBLE (-1700 1725);
FORCEPROP 1 LAST COMMENT_BODY TRUE
J 0
(-2070 1755);
DISPLAY 1.170213 (-2070 1755);
PAINT GREEN (-2070 1755);
DISPLAY INVISIBLE (-2070 1755);
FORCEPROP 2 LAST PATH I154
J 0
(-1850 1925);
DISPLAY 1.021277 (-1850 1925);
PAINT ORANGE (-1850 1925);
DISPLAY INVISIBLE (-1850 1925);
FORCEADD OFFPAGE..2
(-2025 2800);
FORCEPROP 2 LAST $XR0 87 
J 0
(-1836 2800);
DISPLAY 0.638298 (-1836 2800);
PAINT MONO (-1836 2800);
FORCEPROP 2 LAST $XR1 88 
J 0
(-1746 2800);
DISPLAY 0.638298 (-1746 2800);
PAINT MONO (-1746 2800);
FORCEPROP 2 LAST CDS_LIB mstr_standard
J 0
(-2025 2800);
PAINT MONO (-2025 2800);
DISPLAY INVISIBLE (-2025 2800);
FORCEPROP 1 LAST OFFPAGE TRUE
J 0
(-1700 2675);
DISPLAY 1.170213 (-1700 2675);
PAINT GREEN (-1700 2675);
DISPLAY INVISIBLE (-1700 2675);
FORCEPROP 1 LAST COMMENT_BODY TRUE
J 0
(-2070 2705);
DISPLAY 1.170213 (-2070 2705);
PAINT GREEN (-2070 2705);
DISPLAY INVISIBLE (-2070 2705);
FORCEPROP 2 LAST PATH I155
J 0
(-1850 2875);
DISPLAY 1.021277 (-1850 2875);
PAINT ORANGE (-1850 2875);
DISPLAY INVISIBLE (-1850 2875);
FORCEADD OFFPAGE..3
(-2025 3750);
FORCEPROP 2 LAST $XR0 87 
J 0
(-1811 3750);
DISPLAY 0.638298 (-1811 3750);
PAINT MONO (-1811 3750);
FORCEPROP 2 LAST $XR1 88 
J 0
(-1721 3750);
DISPLAY 0.638298 (-1721 3750);
PAINT MONO (-1721 3750);
FORCEPROP 2 LAST CDS_LIB mstr_standard
J 0
(-2025 3750);
PAINT MONO (-2025 3750);
DISPLAY INVISIBLE (-2025 3750);
FORCEPROP 1 LAST OFFPAGE TRUE
J 0
(-1700 3625);
DISPLAY 1.170213 (-1700 3625);
PAINT GREEN (-1700 3625);
DISPLAY INVISIBLE (-1700 3625);
FORCEPROP 1 LAST COMMENT_BODY TRUE
J 0
(-2075 3650);
DISPLAY 1.170213 (-2075 3650);
PAINT GREEN (-2075 3650);
DISPLAY INVISIBLE (-2075 3650);
FORCEPROP 2 LAST PATH I156
J 0
(-1825 3825);
DISPLAY 1.021277 (-1825 3825);
PAINT ORANGE (-1825 3825);
DISPLAY INVISIBLE (-1825 3825);
FORCEADD TAP..6
R 2
(-2875 4000);
FORCEPROP 3 LASTPIN (-2925 4000) SIG_NAME M_M_DQS_DP<4>
J 0
(-2915 4010);
DISPLAY 0.659574 (-2915 4010);
PAINT MONO (-2915 4010);
DISPLAY INVISIBLE (-2915 4010);
FORCEPROP 1 LASTPIN (-2925 4000) BN 4
J 2
(-2873 4008);
DISPLAY 0.617021 (-2873 4008);
PAINT GREEN (-2873 4008);
FORCEPROP 2 LAST CDS_LIB mstr_standard
J 0
(-2875 4000);
PAINT MONO (-2875 4000);
DISPLAY INVISIBLE (-2875 4000);
FORCEPROP 1 LAST BODY_TYPE PLUMBING
J 2
(-2875 3950);
DISPLAY 1.595745 (-2875 3950);
PAINT GREEN (-2875 3950);
DISPLAY INVISIBLE (-2875 3950);
FORCEPROP 1 LAST HDL_TAP TRUE
J 2
(-3200 3875);
DISPLAY 1.595745 (-3200 3875);
PAINT GREEN (-3200 3875);
DISPLAY INVISIBLE (-3200 3875);
FORCEPROP 1 LAST PATH I157
J 2
(-2873 4000);
DISPLAY 0.872340 (-2873 4000);
PAINT GREEN (-2873 4000);
DISPLAY INVISIBLE (-2873 4000);
FORCEADD TAP..6
R 2
(-2875 4100);
FORCEPROP 3 LASTPIN (-2925 4100) SIG_NAME M_M_DQS_DP<6>
J 0
(-2915 4110);
DISPLAY 0.659574 (-2915 4110);
PAINT MONO (-2915 4110);
DISPLAY INVISIBLE (-2915 4110);
FORCEPROP 1 LASTPIN (-2925 4100) BN 6
J 2
(-2873 4108);
DISPLAY 0.617021 (-2873 4108);
PAINT GREEN (-2873 4108);
FORCEPROP 2 LAST CDS_LIB mstr_standard
J 0
(-2875 4100);
PAINT MONO (-2875 4100);
DISPLAY INVISIBLE (-2875 4100);
FORCEPROP 1 LAST BODY_TYPE PLUMBING
J 2
(-2875 4050);
DISPLAY 1.595745 (-2875 4050);
PAINT GREEN (-2875 4050);
DISPLAY INVISIBLE (-2875 4050);
FORCEPROP 1 LAST HDL_TAP TRUE
J 2
(-3200 3975);
DISPLAY 1.595745 (-3200 3975);
PAINT GREEN (-3200 3975);
DISPLAY INVISIBLE (-3200 3975);
FORCEPROP 1 LAST PATH I158
J 2
(-2873 4100);
DISPLAY 0.872340 (-2873 4100);
PAINT GREEN (-2873 4100);
DISPLAY INVISIBLE (-2873 4100);
FORCEADD TAP..6
R 2
(-2875 4050);
FORCEPROP 3 LASTPIN (-2925 4050) SIG_NAME M_M_DQS_DP<5>
J 0
(-2915 4060);
DISPLAY 0.659574 (-2915 4060);
PAINT MONO (-2915 4060);
DISPLAY INVISIBLE (-2915 4060);
FORCEPROP 1 LASTPIN (-2925 4050) BN 5
J 2
(-2873 4058);
DISPLAY 0.617021 (-2873 4058);
PAINT GREEN (-2873 4058);
FORCEPROP 2 LAST CDS_LIB mstr_standard
J 0
(-2875 4050);
PAINT MONO (-2875 4050);
DISPLAY INVISIBLE (-2875 4050);
FORCEPROP 1 LAST BODY_TYPE PLUMBING
J 2
(-2875 4000);
DISPLAY 1.595745 (-2875 4000);
PAINT GREEN (-2875 4000);
DISPLAY INVISIBLE (-2875 4000);
FORCEPROP 1 LAST HDL_TAP TRUE
J 2
(-3200 3925);
DISPLAY 1.595745 (-3200 3925);
PAINT GREEN (-3200 3925);
DISPLAY INVISIBLE (-3200 3925);
FORCEPROP 1 LAST PATH I159
J 2
(-2873 4050);
DISPLAY 0.872340 (-2873 4050);
PAINT GREEN (-2873 4050);
DISPLAY INVISIBLE (-2873 4050);
FORCEADD TAP..6
(-5600 1250);
FORCEPROP 3 LASTPIN (-5550 1250) SIG_NAME M_M_ECC<4>
J 0
(-5540 1260);
DISPLAY 0.659574 (-5540 1260);
PAINT MONO (-5540 1260);
DISPLAY INVISIBLE (-5540 1260);
FORCEPROP 1 LASTPIN (-5550 1250) BN 4
J 0
(-5602 1258);
DISPLAY 0.617021 (-5602 1258);
PAINT GREEN (-5602 1258);
FORCEPROP 2 LAST CDS_LIB mstr_standard
J 0
(-5600 1250);
PAINT MONO (-5600 1250);
DISPLAY INVISIBLE (-5600 1250);
FORCEPROP 1 LAST BODY_TYPE PLUMBING
J 0
(-5600 1200);
DISPLAY 1.595745 (-5600 1200);
PAINT GREEN (-5600 1200);
DISPLAY INVISIBLE (-5600 1200);
FORCEPROP 1 LAST HDL_TAP TRUE
J 0
(-5275 1125);
DISPLAY 1.595745 (-5275 1125);
PAINT GREEN (-5275 1125);
DISPLAY INVISIBLE (-5275 1125);
FORCEPROP 1 LAST PATH I16
J 0
(-5602 1250);
DISPLAY 0.872340 (-5602 1250);
PAINT GREEN (-5602 1250);
DISPLAY INVISIBLE (-5602 1250);
FORCEADD TAP..6
R 2
(-2875 4150);
FORCEPROP 3 LASTPIN (-2925 4150) SIG_NAME M_M_DQS_DP<7>
J 0
(-2915 4160);
DISPLAY 0.659574 (-2915 4160);
PAINT MONO (-2915 4160);
DISPLAY INVISIBLE (-2915 4160);
FORCEPROP 1 LASTPIN (-2925 4150) BN 7
J 2
(-2873 4158);
DISPLAY 0.617021 (-2873 4158);
PAINT GREEN (-2873 4158);
FORCEPROP 2 LAST CDS_LIB mstr_standard
J 0
(-2875 4150);
PAINT MONO (-2875 4150);
DISPLAY INVISIBLE (-2875 4150);
FORCEPROP 1 LAST BODY_TYPE PLUMBING
J 2
(-2875 4100);
DISPLAY 1.595745 (-2875 4100);
PAINT GREEN (-2875 4100);
DISPLAY INVISIBLE (-2875 4100);
FORCEPROP 1 LAST HDL_TAP TRUE
J 2
(-3200 4025);
DISPLAY 1.595745 (-3200 4025);
PAINT GREEN (-3200 4025);
DISPLAY INVISIBLE (-3200 4025);
FORCEPROP 1 LAST PATH I160
J 2
(-2873 4150);
DISPLAY 0.872340 (-2873 4150);
PAINT GREEN (-2873 4150);
DISPLAY INVISIBLE (-2873 4150);
FORCEADD TAP..6
R 2
(-2875 4200);
FORCEPROP 3 LASTPIN (-2925 4200) SIG_NAME M_M_DQS_DP<8>
J 0
(-2915 4210);
DISPLAY 0.659574 (-2915 4210);
PAINT MONO (-2915 4210);
DISPLAY INVISIBLE (-2915 4210);
FORCEPROP 1 LASTPIN (-2925 4200) BN 8
J 2
(-2873 4208);
DISPLAY 0.617021 (-2873 4208);
PAINT GREEN (-2873 4208);
FORCEPROP 2 LAST CDS_LIB mstr_standard
J 0
(-2875 4200);
PAINT MONO (-2875 4200);
DISPLAY INVISIBLE (-2875 4200);
FORCEPROP 1 LAST BODY_TYPE PLUMBING
J 2
(-2875 4150);
DISPLAY 1.595745 (-2875 4150);
PAINT GREEN (-2875 4150);
DISPLAY INVISIBLE (-2875 4150);
FORCEPROP 1 LAST HDL_TAP TRUE
J 2
(-3200 4075);
DISPLAY 1.595745 (-3200 4075);
PAINT GREEN (-3200 4075);
DISPLAY INVISIBLE (-3200 4075);
FORCEPROP 1 LAST PATH I161
J 2
(-2873 4200);
DISPLAY 0.872340 (-2873 4200);
PAINT GREEN (-2873 4200);
DISPLAY INVISIBLE (-2873 4200);
FORCEADD TAP..6
R 2
(-2875 4250);
FORCEPROP 3 LASTPIN (-2925 4250) SIG_NAME M_M_DQS_DP<9>
J 0
(-2915 4260);
DISPLAY 0.659574 (-2915 4260);
PAINT MONO (-2915 4260);
DISPLAY INVISIBLE (-2915 4260);
FORCEPROP 1 LASTPIN (-2925 4250) BN 9
J 2
(-2873 4258);
DISPLAY 0.617021 (-2873 4258);
PAINT GREEN (-2873 4258);
FORCEPROP 2 LAST CDS_LIB mstr_standard
J 0
(-2875 4250);
PAINT MONO (-2875 4250);
DISPLAY INVISIBLE (-2875 4250);
FORCEPROP 1 LAST BODY_TYPE PLUMBING
J 2
(-2875 4200);
DISPLAY 1.595745 (-2875 4200);
PAINT GREEN (-2875 4200);
DISPLAY INVISIBLE (-2875 4200);
FORCEPROP 1 LAST HDL_TAP TRUE
J 2
(-3200 4125);
DISPLAY 1.595745 (-3200 4125);
PAINT GREEN (-3200 4125);
DISPLAY INVISIBLE (-3200 4125);
FORCEPROP 1 LAST PATH I162
J 2
(-2873 4250);
DISPLAY 0.872340 (-2873 4250);
PAINT GREEN (-2873 4250);
DISPLAY INVISIBLE (-2873 4250);
FORCEADD TAP..6
R 2
(-2875 4300);
FORCEPROP 3 LASTPIN (-2925 4300) SIG_NAME M_M_DQS_DP<10>
J 0
(-2915 4310);
DISPLAY 0.659574 (-2915 4310);
PAINT MONO (-2915 4310);
DISPLAY INVISIBLE (-2915 4310);
FORCEPROP 1 LASTPIN (-2925 4300) BN 10
J 2
(-2873 4308);
DISPLAY 0.617021 (-2873 4308);
PAINT GREEN (-2873 4308);
FORCEPROP 2 LAST CDS_LIB mstr_standard
J 0
(-2875 4300);
PAINT MONO (-2875 4300);
DISPLAY INVISIBLE (-2875 4300);
FORCEPROP 1 LAST BODY_TYPE PLUMBING
J 2
(-2875 4250);
DISPLAY 1.595745 (-2875 4250);
PAINT GREEN (-2875 4250);
DISPLAY INVISIBLE (-2875 4250);
FORCEPROP 1 LAST HDL_TAP TRUE
J 2
(-3200 4175);
DISPLAY 1.595745 (-3200 4175);
PAINT GREEN (-3200 4175);
DISPLAY INVISIBLE (-3200 4175);
FORCEPROP 1 LAST PATH I163
J 2
(-2873 4300);
DISPLAY 0.872340 (-2873 4300);
PAINT GREEN (-2873 4300);
DISPLAY INVISIBLE (-2873 4300);
FORCEADD TAP..6
R 2
(-2875 4350);
FORCEPROP 3 LASTPIN (-2925 4350) SIG_NAME M_M_DQS_DP<11>
J 0
(-2915 4360);
DISPLAY 0.659574 (-2915 4360);
PAINT MONO (-2915 4360);
DISPLAY INVISIBLE (-2915 4360);
FORCEPROP 1 LASTPIN (-2925 4350) BN 11
J 2
(-2873 4358);
DISPLAY 0.617021 (-2873 4358);
PAINT GREEN (-2873 4358);
FORCEPROP 2 LAST CDS_LIB mstr_standard
J 0
(-2875 4350);
PAINT MONO (-2875 4350);
DISPLAY INVISIBLE (-2875 4350);
FORCEPROP 1 LAST BODY_TYPE PLUMBING
J 2
(-2875 4300);
DISPLAY 1.595745 (-2875 4300);
PAINT GREEN (-2875 4300);
DISPLAY INVISIBLE (-2875 4300);
FORCEPROP 1 LAST HDL_TAP TRUE
J 2
(-3200 4225);
DISPLAY 1.595745 (-3200 4225);
PAINT GREEN (-3200 4225);
DISPLAY INVISIBLE (-3200 4225);
FORCEPROP 1 LAST PATH I164
J 2
(-2873 4350);
DISPLAY 0.872340 (-2873 4350);
PAINT GREEN (-2873 4350);
DISPLAY INVISIBLE (-2873 4350);
FORCEADD TAP..6
R 2
(-2875 4500);
FORCEPROP 3 LASTPIN (-2925 4500) SIG_NAME M_M_DQS_DP<14>
J 0
(-2915 4510);
DISPLAY 0.659574 (-2915 4510);
PAINT MONO (-2915 4510);
DISPLAY INVISIBLE (-2915 4510);
FORCEPROP 1 LASTPIN (-2925 4500) BN 14
J 2
(-2873 4508);
DISPLAY 0.617021 (-2873 4508);
PAINT GREEN (-2873 4508);
FORCEPROP 2 LAST CDS_LIB mstr_standard
J 0
(-2875 4500);
PAINT MONO (-2875 4500);
DISPLAY INVISIBLE (-2875 4500);
FORCEPROP 1 LAST BODY_TYPE PLUMBING
J 2
(-2875 4450);
DISPLAY 1.595745 (-2875 4450);
PAINT GREEN (-2875 4450);
DISPLAY INVISIBLE (-2875 4450);
FORCEPROP 1 LAST HDL_TAP TRUE
J 2
(-3200 4375);
DISPLAY 1.595745 (-3200 4375);
PAINT GREEN (-3200 4375);
DISPLAY INVISIBLE (-3200 4375);
FORCEPROP 1 LAST PATH I165
J 2
(-2873 4500);
DISPLAY 0.872340 (-2873 4500);
PAINT GREEN (-2873 4500);
DISPLAY INVISIBLE (-2873 4500);
FORCEADD TAP..6
R 2
(-2875 4450);
FORCEPROP 3 LASTPIN (-2925 4450) SIG_NAME M_M_DQS_DP<13>
J 0
(-2915 4460);
DISPLAY 0.659574 (-2915 4460);
PAINT MONO (-2915 4460);
DISPLAY INVISIBLE (-2915 4460);
FORCEPROP 1 LASTPIN (-2925 4450) BN 13
J 2
(-2873 4458);
DISPLAY 0.617021 (-2873 4458);
PAINT GREEN (-2873 4458);
FORCEPROP 2 LAST CDS_LIB mstr_standard
J 0
(-2875 4450);
PAINT MONO (-2875 4450);
DISPLAY INVISIBLE (-2875 4450);
FORCEPROP 1 LAST BODY_TYPE PLUMBING
J 2
(-2875 4400);
DISPLAY 1.595745 (-2875 4400);
PAINT GREEN (-2875 4400);
DISPLAY INVISIBLE (-2875 4400);
FORCEPROP 1 LAST HDL_TAP TRUE
J 2
(-3200 4325);
DISPLAY 1.595745 (-3200 4325);
PAINT GREEN (-3200 4325);
DISPLAY INVISIBLE (-3200 4325);
FORCEPROP 1 LAST PATH I166
J 2
(-2873 4450);
DISPLAY 0.872340 (-2873 4450);
PAINT GREEN (-2873 4450);
DISPLAY INVISIBLE (-2873 4450);
FORCEADD TAP..6
R 2
(-2875 4400);
FORCEPROP 3 LASTPIN (-2925 4400) SIG_NAME M_M_DQS_DP<12>
J 0
(-2915 4410);
DISPLAY 0.659574 (-2915 4410);
PAINT MONO (-2915 4410);
DISPLAY INVISIBLE (-2915 4410);
FORCEPROP 1 LASTPIN (-2925 4400) BN 12
J 2
(-2873 4408);
DISPLAY 0.617021 (-2873 4408);
PAINT GREEN (-2873 4408);
FORCEPROP 2 LAST CDS_LIB mstr_standard
J 0
(-2875 4400);
PAINT MONO (-2875 4400);
DISPLAY INVISIBLE (-2875 4400);
FORCEPROP 1 LAST BODY_TYPE PLUMBING
J 2
(-2875 4350);
DISPLAY 1.595745 (-2875 4350);
PAINT GREEN (-2875 4350);
DISPLAY INVISIBLE (-2875 4350);
FORCEPROP 1 LAST HDL_TAP TRUE
J 2
(-3200 4275);
DISPLAY 1.595745 (-3200 4275);
PAINT GREEN (-3200 4275);
DISPLAY INVISIBLE (-3200 4275);
FORCEPROP 1 LAST PATH I167
J 2
(-2873 4400);
DISPLAY 0.872340 (-2873 4400);
PAINT GREEN (-2873 4400);
DISPLAY INVISIBLE (-2873 4400);
FORCEADD TAP..6
R 2
(-2875 4550);
FORCEPROP 3 LASTPIN (-2925 4550) SIG_NAME M_M_DQS_DP<15>
J 0
(-2915 4560);
DISPLAY 0.659574 (-2915 4560);
PAINT MONO (-2915 4560);
DISPLAY INVISIBLE (-2915 4560);
FORCEPROP 1 LASTPIN (-2925 4550) BN 15
J 2
(-2873 4558);
DISPLAY 0.617021 (-2873 4558);
PAINT GREEN (-2873 4558);
FORCEPROP 2 LAST CDS_LIB mstr_standard
J 0
(-2875 4550);
PAINT MONO (-2875 4550);
DISPLAY INVISIBLE (-2875 4550);
FORCEPROP 1 LAST BODY_TYPE PLUMBING
J 2
(-2875 4500);
DISPLAY 1.595745 (-2875 4500);
PAINT GREEN (-2875 4500);
DISPLAY INVISIBLE (-2875 4500);
FORCEPROP 1 LAST HDL_TAP TRUE
J 2
(-3200 4425);
DISPLAY 1.595745 (-3200 4425);
PAINT GREEN (-3200 4425);
DISPLAY INVISIBLE (-3200 4425);
FORCEPROP 1 LAST PATH I168
J 2
(-2873 4550);
DISPLAY 0.872340 (-2873 4550);
PAINT GREEN (-2873 4550);
DISPLAY INVISIBLE (-2873 4550);
FORCEADD TAP..6
R 2
(-2875 4600);
FORCEPROP 3 LASTPIN (-2925 4600) SIG_NAME M_M_DQS_DP<16>
J 0
(-2915 4610);
DISPLAY 0.659574 (-2915 4610);
PAINT MONO (-2915 4610);
DISPLAY INVISIBLE (-2915 4610);
FORCEPROP 1 LASTPIN (-2925 4600) BN 16
J 2
(-2873 4608);
DISPLAY 0.617021 (-2873 4608);
PAINT GREEN (-2873 4608);
FORCEPROP 2 LAST CDS_LIB mstr_standard
J 0
(-2875 4600);
PAINT MONO (-2875 4600);
DISPLAY INVISIBLE (-2875 4600);
FORCEPROP 1 LAST BODY_TYPE PLUMBING
J 2
(-2875 4550);
DISPLAY 1.595745 (-2875 4550);
PAINT GREEN (-2875 4550);
DISPLAY INVISIBLE (-2875 4550);
FORCEPROP 1 LAST HDL_TAP TRUE
J 2
(-3200 4475);
DISPLAY 1.595745 (-3200 4475);
PAINT GREEN (-3200 4475);
DISPLAY INVISIBLE (-3200 4475);
FORCEPROP 1 LAST PATH I169
J 2
(-2873 4600);
DISPLAY 0.872340 (-2873 4600);
PAINT GREEN (-2873 4600);
DISPLAY INVISIBLE (-2873 4600);
FORCEADD TAP..6
(-5600 1200);
FORCEPROP 3 LASTPIN (-5550 1200) SIG_NAME M_M_ECC<3>
J 0
(-5540 1210);
DISPLAY 0.659574 (-5540 1210);
PAINT MONO (-5540 1210);
DISPLAY INVISIBLE (-5540 1210);
FORCEPROP 1 LASTPIN (-5550 1200) BN 3
J 0
(-5602 1208);
DISPLAY 0.617021 (-5602 1208);
PAINT GREEN (-5602 1208);
FORCEPROP 2 LAST CDS_LIB mstr_standard
J 0
(-5600 1200);
PAINT MONO (-5600 1200);
DISPLAY INVISIBLE (-5600 1200);
FORCEPROP 1 LAST BODY_TYPE PLUMBING
J 0
(-5600 1150);
DISPLAY 1.595745 (-5600 1150);
PAINT GREEN (-5600 1150);
DISPLAY INVISIBLE (-5600 1150);
FORCEPROP 1 LAST HDL_TAP TRUE
J 0
(-5275 1075);
DISPLAY 1.595745 (-5275 1075);
PAINT GREEN (-5275 1075);
DISPLAY INVISIBLE (-5275 1075);
FORCEPROP 1 LAST PATH I17
J 0
(-5602 1200);
DISPLAY 0.872340 (-5602 1200);
PAINT GREEN (-5602 1200);
DISPLAY INVISIBLE (-5602 1200);
FORCEADD TAP..6
R 2
(-2875 4650);
FORCEPROP 3 LASTPIN (-2925 4650) SIG_NAME M_M_DQS_DP<17>
J 0
(-2915 4660);
DISPLAY 0.659574 (-2915 4660);
PAINT MONO (-2915 4660);
DISPLAY INVISIBLE (-2915 4660);
FORCEPROP 1 LASTPIN (-2925 4650) BN 17
J 2
(-2873 4658);
DISPLAY 0.617021 (-2873 4658);
PAINT GREEN (-2873 4658);
FORCEPROP 2 LAST CDS_LIB mstr_standard
J 2
(-2875 4650);
PAINT MONO (-2875 4650);
DISPLAY INVISIBLE (-2875 4650);
FORCEPROP 1 LAST BODY_TYPE PLUMBING
J 2
(-2875 4600);
DISPLAY 1.595745 (-2875 4600);
PAINT GREEN (-2875 4600);
DISPLAY INVISIBLE (-2875 4600);
FORCEPROP 1 LAST HDL_TAP TRUE
J 2
(-3200 4525);
DISPLAY 1.595745 (-3200 4525);
PAINT GREEN (-3200 4525);
DISPLAY INVISIBLE (-3200 4525);
FORCEPROP 1 LAST PATH I170
J 2
(-2873 4650);
DISPLAY 0.872340 (-2873 4650);
PAINT GREEN (-2873 4650);
DISPLAY INVISIBLE (-2873 4650);
FORCEADD OFFPAGE..3
(-2025 4725);
FORCEPROP 2 LAST $XR0 87 
J 0
(-1811 4725);
DISPLAY 0.638298 (-1811 4725);
PAINT MONO (-1811 4725);
FORCEPROP 2 LAST $XR1 88 
J 0
(-1721 4725);
DISPLAY 0.638298 (-1721 4725);
PAINT MONO (-1721 4725);
FORCEPROP 2 LAST CDS_LIB mstr_standard
J 0
(-2025 4725);
PAINT MONO (-2025 4725);
DISPLAY INVISIBLE (-2025 4725);
FORCEPROP 1 LAST OFFPAGE TRUE
J 0
(-1700 4600);
DISPLAY 1.170213 (-1700 4600);
PAINT GREEN (-1700 4600);
DISPLAY INVISIBLE (-1700 4600);
FORCEPROP 1 LAST COMMENT_BODY TRUE
J 0
(-2075 4625);
DISPLAY 1.170213 (-2075 4625);
PAINT GREEN (-2075 4625);
DISPLAY INVISIBLE (-2075 4625);
FORCEPROP 2 LAST PATH I171
J 0
(-1825 4800);
DISPLAY 1.021277 (-1825 4800);
PAINT ORANGE (-1825 4800);
DISPLAY INVISIBLE (-1825 4800);
FORCEADD SKX_EXT_B..8
(-4200 2550);
FORCEPROP 1 LAST LOCATION U2D1
J 0
(-5000 4900);
DISPLAY 0.617021 (-5000 4900);
PAINT AQUA (-5000 4900);
FORCEPROP 1 LAST PART_NUMBER TBD
J 0
(-5000 300);
DISPLAY 0.617021 (-5000 300);
PAINT BLUE (-5000 300);
FORCEPROP 1 LAST MATERIAL IC
J 0
(-5000 4850);
DISPLAY 0.617021 (-5000 4850);
PAINT SKYBLUE (-5000 4850);
FORCEPROP 2 LASTPIN (-3350 500) $PN DK53
J 0
(-3340 510);
DISPLAY 0.617021 (-3340 510);
PAINT ORANGE (-3340 510);
FORCEPROP 2 LASTPIN (-3350 1550) $PN DF47
J 0
(-3340 1560);
DISPLAY 0.617021 (-3340 1560);
PAINT ORANGE (-3340 1560);
FORCEPROP 2 LASTPIN (-3350 1500) $PN DK49
J 0
(-3340 1510);
DISPLAY 0.617021 (-3340 1510);
PAINT ORANGE (-3340 1510);
FORCEPROP 2 LASTPIN (-3350 1450) $PN DG48
J 0
(-3340 1460);
DISPLAY 0.617021 (-3340 1460);
PAINT ORANGE (-3340 1460);
FORCEPROP 2 LASTPIN (-3350 1400) $PN DG50
J 0
(-3340 1410);
DISPLAY 0.617021 (-3340 1410);
PAINT ORANGE (-3340 1410);
FORCEPROP 2 LASTPIN (-3350 2750) $PN DE46
J 0
(-3340 2760);
DISPLAY 0.617021 (-3340 2760);
PAINT ORANGE (-3340 2760);
FORCEPROP 2 LASTPIN (-3350 2700) $PN DG52
J 0
(-3340 2710);
DISPLAY 0.617021 (-3340 2710);
PAINT ORANGE (-3340 2710);
FORCEPROP 2 LASTPIN (-3350 2650) $PN DC54
J 0
(-3340 2660);
DISPLAY 0.617021 (-3340 2660);
PAINT ORANGE (-3340 2660);
FORCEPROP 2 LASTPIN (-3350 2600) $PN DJ50
J 0
(-3340 2610);
DISPLAY 0.617021 (-3340 2610);
PAINT ORANGE (-3340 2610);
FORCEPROP 2 LASTPIN (-3350 2550) $PN DD53
J 0
(-3340 2560);
DISPLAY 0.617021 (-3340 2560);
PAINT ORANGE (-3340 2560);
FORCEPROP 2 LASTPIN (-3350 2500) $PN DG60
J 0
(-3340 2510);
DISPLAY 0.617021 (-3340 2510);
PAINT ORANGE (-3340 2510);
FORCEPROP 2 LASTPIN (-3350 2450) $PN DA60
J 0
(-3340 2460);
DISPLAY 0.617021 (-3340 2460);
PAINT ORANGE (-3340 2460);
FORCEPROP 2 LASTPIN (-3350 2400) $PN DD55
J 0
(-3340 2410);
DISPLAY 0.617021 (-3340 2410);
PAINT ORANGE (-3340 2410);
FORCEPROP 2 LASTPIN (-3350 2350) $PN DA58
J 0
(-3340 2360);
DISPLAY 0.617021 (-3340 2360);
PAINT ORANGE (-3340 2360);
FORCEPROP 2 LASTPIN (-3350 2300) $PN DD59
J 0
(-3340 2310);
DISPLAY 0.617021 (-3340 2310);
PAINT ORANGE (-3340 2310);
FORCEPROP 2 LASTPIN (-3350 2250) $PN DC60
J 0
(-3340 2260);
DISPLAY 0.617021 (-3340 2260);
PAINT ORANGE (-3340 2260);
FORCEPROP 2 LASTPIN (-3350 2200) $PN DK59
J 0
(-3340 2210);
DISPLAY 0.617021 (-3340 2210);
PAINT ORANGE (-3340 2210);
FORCEPROP 2 LASTPIN (-3350 2150) $PN DF59
J 0
(-3340 2160);
DISPLAY 0.617021 (-3340 2160);
PAINT ORANGE (-3340 2160);
FORCEPROP 2 LASTPIN (-3350 2100) $PN DJ58
J 0
(-3340 2110);
DISPLAY 0.617021 (-3340 2110);
PAINT ORANGE (-3340 2110);
FORCEPROP 2 LASTPIN (-3350 2050) $PN DG58
J 0
(-3340 2060);
DISPLAY 0.617021 (-3340 2060);
PAINT ORANGE (-3340 2060);
FORCEPROP 2 LASTPIN (-3350 2000) $PN DD57
J 0
(-3340 2010);
DISPLAY 0.617021 (-3340 2010);
PAINT ORANGE (-3340 2010);
FORCEPROP 2 LASTPIN (-3350 1950) $PN DC58
J 0
(-3340 1960);
DISPLAY 0.617021 (-3340 1960);
PAINT ORANGE (-3340 1960);
FORCEPROP 2 LASTPIN (-3350 1900) $PN DF53
J 0
(-3340 1910);
DISPLAY 0.617021 (-3340 1910);
PAINT ORANGE (-3340 1910);
FORCEPROP 2 LASTPIN (-5050 1400) $PN CM69
J 2
(-5060 1410);
DISPLAY 0.617021 (-5060 1410);
PAINT ORANGE (-5060 1410);
FORCEPROP 2 LASTPIN (-5050 1350) $PN CH69
J 2
(-5060 1360);
DISPLAY 0.617021 (-5060 1360);
PAINT ORANGE (-5060 1360);
FORCEPROP 2 LASTPIN (-5050 1300) $PN CL72
J 2
(-5060 1310);
DISPLAY 0.617021 (-5060 1310);
PAINT ORANGE (-5060 1310);
FORCEPROP 2 LASTPIN (-5050 1250) $PN CJ72
J 2
(-5060 1260);
DISPLAY 0.617021 (-5060 1260);
PAINT ORANGE (-5060 1260);
FORCEPROP 2 LASTPIN (-5050 1200) $PN CL68
J 2
(-5060 1210);
DISPLAY 0.617021 (-5060 1210);
PAINT ORANGE (-5060 1210);
FORCEPROP 2 LASTPIN (-5050 1150) $PN CJ68
J 2
(-5060 1160);
DISPLAY 0.617021 (-5060 1160);
PAINT ORANGE (-5060 1160);
FORCEPROP 2 LASTPIN (-5050 1100) $PN CM71
J 2
(-5060 1110);
DISPLAY 0.617021 (-5060 1110);
PAINT ORANGE (-5060 1110);
FORCEPROP 2 LASTPIN (-5050 1050) $PN CH71
J 2
(-5060 1060);
DISPLAY 0.617021 (-5060 1060);
PAINT ORANGE (-5060 1060);
FORCEPROP 2 LASTPIN (-3350 4650) $PN CG70
J 0
(-3340 4660);
DISPLAY 0.617021 (-3340 4660);
PAINT ORANGE (-3340 4660);
FORCEPROP 2 LASTPIN (-3350 4600) $PN CV29
J 0
(-3340 4610);
DISPLAY 0.617021 (-3340 4610);
PAINT ORANGE (-3340 4610);
FORCEPROP 2 LASTPIN (-3350 4550) $PN CV35
J 0
(-3340 4560);
DISPLAY 0.617021 (-3340 4560);
PAINT ORANGE (-3340 4560);
FORCEPROP 2 LASTPIN (-3350 4500) $PN DE32
J 0
(-3340 4510);
DISPLAY 0.617021 (-3340 4510);
PAINT ORANGE (-3340 4510);
FORCEPROP 2 LASTPIN (-3350 4450) $PN DC40
J 0
(-3340 4460);
DISPLAY 0.617021 (-3340 4460);
PAINT ORANGE (-3340 4460);
FORCEPROP 2 LASTPIN (-3350 4400) $PN CM65
J 0
(-3340 4410);
DISPLAY 0.617021 (-3340 4410);
PAINT ORANGE (-3340 4410);
FORCEPROP 2 LASTPIN (-3350 4350) $PN DH69
J 0
(-3340 4360);
DISPLAY 0.617021 (-3340 4360);
PAINT ORANGE (-3340 4360);
FORCEPROP 2 LASTPIN (-3350 4300) $PN DG74
J 0
(-3340 4310);
DISPLAY 0.617021 (-3340 4310);
PAINT ORANGE (-3340 4310);
FORCEPROP 2 LASTPIN (-3350 4250) $PN CU74
J 0
(-3340 4260);
DISPLAY 0.617021 (-3340 4260);
PAINT ORANGE (-3340 4260);
FORCEPROP 2 LASTPIN (-3350 4200) $PN CL70
J 0
(-3340 4210);
DISPLAY 0.617021 (-3340 4210);
PAINT ORANGE (-3340 4210);
FORCEPROP 2 LASTPIN (-3350 4150) $PN DB29
J 0
(-3340 4160);
DISPLAY 0.617021 (-3340 4160);
PAINT ORANGE (-3340 4160);
FORCEPROP 2 LASTPIN (-3350 4100) $PN DB35
J 0
(-3340 4110);
DISPLAY 0.617021 (-3340 4110);
PAINT ORANGE (-3340 4110);
FORCEPROP 2 LASTPIN (-3350 4050) $PN DJ32
J 0
(-3340 4060);
DISPLAY 0.617021 (-3340 4060);
PAINT ORANGE (-3340 4060);
FORCEPROP 2 LASTPIN (-3350 4000) $PN DJ40
J 0
(-3340 4010);
DISPLAY 0.617021 (-3340 4010);
PAINT ORANGE (-3340 4010);
FORCEPROP 2 LASTPIN (-3350 3950) $PN CT65
J 0
(-3340 3960);
DISPLAY 0.617021 (-3340 3960);
PAINT ORANGE (-3340 3960);
FORCEPROP 2 LASTPIN (-3350 3900) $PN DK71
J 0
(-3340 3910);
DISPLAY 0.617021 (-3340 3910);
PAINT ORANGE (-3340 3910);
FORCEPROP 2 LASTPIN (-3350 3850) $PN DE76
J 0
(-3340 3860);
DISPLAY 0.617021 (-3340 3860);
PAINT ORANGE (-3340 3860);
FORCEPROP 2 LASTPIN (-3350 3800) $PN CR76
J 0
(-3340 3810);
DISPLAY 0.617021 (-3340 3810);
PAINT ORANGE (-3340 3810);
FORCEPROP 2 LASTPIN (-3350 3700) $PN CJ70
J 0
(-3340 3710);
DISPLAY 0.617021 (-3340 3710);
PAINT ORANGE (-3340 3710);
FORCEPROP 2 LASTPIN (-3350 3650) $PN CY29
J 0
(-3340 3660);
DISPLAY 0.617021 (-3340 3660);
PAINT ORANGE (-3340 3660);
FORCEPROP 2 LASTPIN (-3350 3600) $PN CY35
J 0
(-3340 3610);
DISPLAY 0.617021 (-3340 3610);
PAINT ORANGE (-3340 3610);
FORCEPROP 2 LASTPIN (-3350 3550) $PN DG32
J 0
(-3340 3560);
DISPLAY 0.617021 (-3340 3560);
PAINT ORANGE (-3340 3560);
FORCEPROP 2 LASTPIN (-3350 3500) $PN DE40
J 0
(-3340 3510);
DISPLAY 0.617021 (-3340 3510);
PAINT ORANGE (-3340 3510);
FORCEPROP 2 LASTPIN (-3350 3450) $PN CP65
J 0
(-3340 3460);
DISPLAY 0.617021 (-3340 3460);
PAINT ORANGE (-3340 3460);
FORCEPROP 2 LASTPIN (-3350 3400) $PN DJ70
J 0
(-3340 3410);
DISPLAY 0.617021 (-3340 3410);
PAINT ORANGE (-3340 3410);
FORCEPROP 2 LASTPIN (-3350 3350) $PN DF75
J 0
(-3340 3360);
DISPLAY 0.617021 (-3340 3360);
PAINT ORANGE (-3340 3360);
FORCEPROP 2 LASTPIN (-3350 3300) $PN CT75
J 0
(-3340 3310);
DISPLAY 0.617021 (-3340 3310);
PAINT ORANGE (-3340 3310);
FORCEPROP 2 LASTPIN (-3350 3250) $PN CN70
J 0
(-3340 3260);
DISPLAY 0.617021 (-3340 3260);
PAINT ORANGE (-3340 3260);
FORCEPROP 2 LASTPIN (-3350 3200) $PN DD29
J 0
(-3340 3210);
DISPLAY 0.617021 (-3340 3210);
PAINT ORANGE (-3340 3210);
FORCEPROP 2 LASTPIN (-3350 3150) $PN DD35
J 0
(-3340 3160);
DISPLAY 0.617021 (-3340 3160);
PAINT ORANGE (-3340 3160);
FORCEPROP 2 LASTPIN (-3350 3100) $PN DL32
J 0
(-3340 3110);
DISPLAY 0.617021 (-3340 3110);
PAINT ORANGE (-3340 3110);
FORCEPROP 2 LASTPIN (-3350 3050) $PN DG40
J 0
(-3340 3060);
DISPLAY 0.617021 (-3340 3060);
PAINT ORANGE (-3340 3060);
FORCEPROP 2 LASTPIN (-3350 3000) $PN CV65
J 0
(-3340 3010);
DISPLAY 0.617021 (-3340 3010);
PAINT ORANGE (-3340 3010);
FORCEPROP 2 LASTPIN (-3350 2950) $PN DL72
J 0
(-3340 2960);
DISPLAY 0.617021 (-3340 2960);
PAINT ORANGE (-3340 2960);
FORCEPROP 2 LASTPIN (-3350 2900) $PN DD77
J 0
(-3340 2910);
DISPLAY 0.617021 (-3340 2910);
PAINT ORANGE (-3340 2910);
FORCEPROP 2 LASTPIN (-3350 2850) $PN CP77
J 0
(-3340 2860);
DISPLAY 0.617021 (-3340 2860);
PAINT ORANGE (-3340 2860);
FORCEPROP 2 LASTPIN (-5050 4650) $PN DC28
J 2
(-5060 4660);
DISPLAY 0.617021 (-5060 4660);
PAINT ORANGE (-5060 4660);
FORCEPROP 2 LASTPIN (-5050 4600) $PN CW28
J 2
(-5060 4610);
DISPLAY 0.617021 (-5060 4610);
PAINT ORANGE (-5060 4610);
FORCEPROP 2 LASTPIN (-5050 4550) $PN DB31
J 2
(-5060 4560);
DISPLAY 0.617021 (-5060 4560);
PAINT ORANGE (-5060 4560);
FORCEPROP 2 LASTPIN (-5050 4500) $PN CY31
J 2
(-5060 4510);
DISPLAY 0.617021 (-5060 4510);
PAINT ORANGE (-5060 4510);
FORCEPROP 2 LASTPIN (-5050 4450) $PN DB27
J 2
(-5060 4460);
DISPLAY 0.617021 (-5060 4460);
PAINT ORANGE (-5060 4460);
FORCEPROP 2 LASTPIN (-5050 4400) $PN CY27
J 2
(-5060 4410);
DISPLAY 0.617021 (-5060 4410);
PAINT ORANGE (-5060 4410);
FORCEPROP 2 LASTPIN (-5050 4350) $PN DC30
J 2
(-5060 4360);
DISPLAY 0.617021 (-5060 4360);
PAINT ORANGE (-5060 4360);
FORCEPROP 2 LASTPIN (-5050 4300) $PN CW30
J 2
(-5060 4310);
DISPLAY 0.617021 (-5060 4310);
PAINT ORANGE (-5060 4310);
FORCEPROP 2 LASTPIN (-5050 4250) $PN DC34
J 2
(-5060 4260);
DISPLAY 0.617021 (-5060 4260);
PAINT ORANGE (-5060 4260);
FORCEPROP 2 LASTPIN (-5050 4200) $PN CW34
J 2
(-5060 4210);
DISPLAY 0.617021 (-5060 4210);
PAINT ORANGE (-5060 4210);
FORCEPROP 2 LASTPIN (-5050 4150) $PN DB37
J 2
(-5060 4160);
DISPLAY 0.617021 (-5060 4160);
PAINT ORANGE (-5060 4160);
FORCEPROP 2 LASTPIN (-5050 4100) $PN CY37
J 2
(-5060 4110);
DISPLAY 0.617021 (-5060 4110);
PAINT ORANGE (-5060 4110);
FORCEPROP 2 LASTPIN (-5050 4050) $PN DB33
J 2
(-5060 4060);
DISPLAY 0.617021 (-5060 4060);
PAINT ORANGE (-5060 4060);
FORCEPROP 2 LASTPIN (-5050 4000) $PN CY33
J 2
(-5060 4010);
DISPLAY 0.617021 (-5060 4010);
PAINT ORANGE (-5060 4010);
FORCEPROP 2 LASTPIN (-5050 3950) $PN DC36
J 2
(-5060 3960);
DISPLAY 0.617021 (-5060 3960);
PAINT ORANGE (-5060 3960);
FORCEPROP 2 LASTPIN (-5050 3900) $PN CW36
J 2
(-5060 3910);
DISPLAY 0.617021 (-5060 3910);
PAINT ORANGE (-5060 3910);
FORCEPROP 2 LASTPIN (-5050 3850) $PN DK31
J 2
(-5060 3860);
DISPLAY 0.617021 (-5060 3860);
PAINT ORANGE (-5060 3860);
FORCEPROP 2 LASTPIN (-5050 3800) $PN DF31
J 2
(-5060 3810);
DISPLAY 0.617021 (-5060 3810);
PAINT ORANGE (-5060 3810);
FORCEPROP 2 LASTPIN (-5050 3750) $PN DJ34
J 2
(-5060 3760);
DISPLAY 0.617021 (-5060 3760);
PAINT ORANGE (-5060 3760);
FORCEPROP 2 LASTPIN (-5050 3700) $PN DG34
J 2
(-5060 3710);
DISPLAY 0.617021 (-5060 3710);
PAINT ORANGE (-5060 3710);
FORCEPROP 2 LASTPIN (-5050 3650) $PN DJ30
J 2
(-5060 3660);
DISPLAY 0.617021 (-5060 3660);
PAINT ORANGE (-5060 3660);
FORCEPROP 2 LASTPIN (-5050 3600) $PN DG30
J 2
(-5060 3610);
DISPLAY 0.617021 (-5060 3610);
PAINT ORANGE (-5060 3610);
FORCEPROP 2 LASTPIN (-5050 3550) $PN DK33
J 2
(-5060 3560);
DISPLAY 0.617021 (-5060 3560);
PAINT ORANGE (-5060 3560);
FORCEPROP 2 LASTPIN (-5050 3500) $PN DF33
J 2
(-5060 3510);
DISPLAY 0.617021 (-5060 3510);
PAINT ORANGE (-5060 3510);
FORCEPROP 2 LASTPIN (-5050 3450) $PN DH39
J 2
(-5060 3460);
DISPLAY 0.617021 (-5060 3460);
PAINT ORANGE (-5060 3460);
FORCEPROP 2 LASTPIN (-5050 3400) $PN DD39
J 2
(-5060 3410);
DISPLAY 0.617021 (-5060 3410);
PAINT ORANGE (-5060 3410);
FORCEPROP 2 LASTPIN (-5050 3350) $PN DE42
J 2
(-5060 3360);
DISPLAY 0.617021 (-5060 3360);
PAINT ORANGE (-5060 3360);
FORCEPROP 2 LASTPIN (-5050 3300) $PN DA42
J 2
(-5060 3310);
DISPLAY 0.617021 (-5060 3310);
PAINT ORANGE (-5060 3310);
FORCEPROP 2 LASTPIN (-5050 3250) $PN DG38
J 2
(-5060 3260);
DISPLAY 0.617021 (-5060 3260);
PAINT ORANGE (-5060 3260);
FORCEPROP 2 LASTPIN (-5050 3200) $PN DE38
J 2
(-5060 3210);
DISPLAY 0.617021 (-5060 3210);
PAINT ORANGE (-5060 3210);
FORCEPROP 2 LASTPIN (-5050 3150) $PN DG42
J 2
(-5060 3160);
DISPLAY 0.617021 (-5060 3160);
PAINT ORANGE (-5060 3160);
FORCEPROP 2 LASTPIN (-5050 3100) $PN DD41
J 2
(-5060 3110);
DISPLAY 0.617021 (-5060 3110);
PAINT ORANGE (-5060 3110);
FORCEPROP 2 LASTPIN (-5050 3050) $PN CU64
J 2
(-5060 3060);
DISPLAY 0.617021 (-5060 3060);
PAINT ORANGE (-5060 3060);
FORCEPROP 2 LASTPIN (-5050 3000) $PN CN64
J 2
(-5060 3010);
DISPLAY 0.617021 (-5060 3010);
PAINT ORANGE (-5060 3010);
FORCEPROP 2 LASTPIN (-5050 2950) $PN CT67
J 2
(-5060 2960);
DISPLAY 0.617021 (-5060 2960);
PAINT ORANGE (-5060 2960);
FORCEPROP 2 LASTPIN (-5050 2900) $PN CP67
J 2
(-5060 2910);
DISPLAY 0.617021 (-5060 2910);
PAINT ORANGE (-5060 2910);
FORCEPROP 2 LASTPIN (-5050 2850) $PN CT63
J 2
(-5060 2860);
DISPLAY 0.617021 (-5060 2860);
PAINT ORANGE (-5060 2860);
FORCEPROP 2 LASTPIN (-5050 2800) $PN CP63
J 2
(-5060 2810);
DISPLAY 0.617021 (-5060 2810);
PAINT ORANGE (-5060 2810);
FORCEPROP 2 LASTPIN (-5050 2750) $PN CU66
J 2
(-5060 2760);
DISPLAY 0.617021 (-5060 2760);
PAINT ORANGE (-5060 2760);
FORCEPROP 2 LASTPIN (-5050 2700) $PN CN66
J 2
(-5060 2710);
DISPLAY 0.617021 (-5060 2710);
PAINT ORANGE (-5060 2710);
FORCEPROP 2 LASTPIN (-5050 2650) $PN DM71
J 2
(-5060 2660);
DISPLAY 0.617021 (-5060 2660);
PAINT ORANGE (-5060 2660);
FORCEPROP 2 LASTPIN (-5050 2600) $PN DK69
J 2
(-5060 2610);
DISPLAY 0.617021 (-5060 2610);
PAINT ORANGE (-5060 2610);
FORCEPROP 2 LASTPIN (-5050 2550) $PN DG72
J 2
(-5060 2560);
DISPLAY 0.617021 (-5060 2560);
PAINT ORANGE (-5060 2560);
FORCEPROP 2 LASTPIN (-5050 2500) $PN DF71
J 2
(-5060 2510);
DISPLAY 0.617021 (-5060 2510);
PAINT ORANGE (-5060 2510);
FORCEPROP 2 LASTPIN (-5050 2450) $PN DN70
J 2
(-5060 2460);
DISPLAY 0.617021 (-5060 2460);
PAINT ORANGE (-5060 2460);
FORCEPROP 2 LASTPIN (-5050 2400) $PN DM69
J 2
(-5060 2410);
DISPLAY 0.617021 (-5060 2410);
PAINT ORANGE (-5060 2410);
FORCEPROP 2 LASTPIN (-5050 2350) $PN DJ72
J 2
(-5060 2360);
DISPLAY 0.617021 (-5060 2360);
PAINT ORANGE (-5060 2360);
FORCEPROP 2 LASTPIN (-5050 2300) $PN DG70
J 2
(-5060 2310);
DISPLAY 0.617021 (-5060 2310);
PAINT ORANGE (-5060 2310);
FORCEPROP 2 LASTPIN (-5050 2250) $PN DH77
J 2
(-5060 2260);
DISPLAY 0.617021 (-5060 2260);
PAINT ORANGE (-5060 2260);
FORCEPROP 2 LASTPIN (-5050 2200) $PN DF77
J 2
(-5060 2210);
DISPLAY 0.617021 (-5060 2210);
PAINT ORANGE (-5060 2210);
FORCEPROP 2 LASTPIN (-5050 2150) $PN DB75
J 2
(-5060 2160);
DISPLAY 0.617021 (-5060 2160);
PAINT ORANGE (-5060 2160);
FORCEPROP 2 LASTPIN (-5050 2100) $PN DC74
J 2
(-5060 2110);
DISPLAY 0.617021 (-5060 2110);
PAINT ORANGE (-5060 2110);
FORCEPROP 2 LASTPIN (-5050 2050) $PN DJ76
J 2
(-5060 2060);
DISPLAY 0.617021 (-5060 2060);
PAINT ORANGE (-5060 2060);
FORCEPROP 2 LASTPIN (-5050 2000) $PN DH75
J 2
(-5060 2010);
DISPLAY 0.617021 (-5060 2010);
PAINT ORANGE (-5060 2010);
FORCEPROP 2 LASTPIN (-5050 1950) $PN DC76
J 2
(-5060 1960);
DISPLAY 0.617021 (-5060 1960);
PAINT ORANGE (-5060 1960);
FORCEPROP 2 LASTPIN (-5050 1900) $PN DE74
J 2
(-5060 1910);
DISPLAY 0.617021 (-5060 1910);
PAINT ORANGE (-5060 1910);
FORCEPROP 2 LASTPIN (-5050 1850) $PN CT77
J 2
(-5060 1860);
DISPLAY 0.617021 (-5060 1860);
PAINT ORANGE (-5060 1860);
FORCEPROP 2 LASTPIN (-5050 1800) $PN CV75
J 2
(-5060 1810);
DISPLAY 0.617021 (-5060 1810);
PAINT ORANGE (-5060 1810);
FORCEPROP 2 LASTPIN (-5050 1750) $PN CM75
J 2
(-5060 1760);
DISPLAY 0.617021 (-5060 1760);
PAINT ORANGE (-5060 1760);
FORCEPROP 2 LASTPIN (-5050 1700) $PN CN74
J 2
(-5060 1710);
DISPLAY 0.617021 (-5060 1710);
PAINT ORANGE (-5060 1710);
FORCEPROP 2 LASTPIN (-5050 1650) $PN CV77
J 2
(-5060 1660);
DISPLAY 0.617021 (-5060 1660);
PAINT ORANGE (-5060 1660);
FORCEPROP 2 LASTPIN (-5050 1600) $PN CW76
J 2
(-5060 1610);
DISPLAY 0.617021 (-5060 1610);
PAINT ORANGE (-5060 1610);
FORCEPROP 2 LASTPIN (-5050 1550) $PN CN76
J 2
(-5060 1560);
DISPLAY 0.617021 (-5060 1560);
PAINT ORANGE (-5060 1560);
FORCEPROP 2 LASTPIN (-5050 1500) $PN CR74
J 2
(-5060 1510);
DISPLAY 0.617021 (-5060 1510);
PAINT ORANGE (-5060 1510);
FORCEPROP 2 LASTPIN (-3350 1300) $PN DK45
J 0
(-3340 1310);
DISPLAY 0.617021 (-3340 1310);
PAINT ORANGE (-3340 1310);
FORCEPROP 2 LASTPIN (-3350 1250) $PN DM45
J 0
(-3340 1260);
DISPLAY 0.617021 (-3340 1260);
PAINT ORANGE (-3340 1260);
FORCEPROP 2 LASTPIN (-3350 1200) $PN DJ48
J 0
(-3340 1210);
DISPLAY 0.617021 (-3340 1210);
PAINT ORANGE (-3340 1210);
FORCEPROP 2 LASTPIN (-3350 1150) $PN DF51
J 0
(-3340 1160);
DISPLAY 0.617021 (-3340 1160);
PAINT ORANGE (-3340 1160);
FORCEPROP 2 LASTPIN (-3350 1100) $PN DG46
J 0
(-3340 1110);
DISPLAY 0.617021 (-3340 1110);
PAINT ORANGE (-3340 1110);
FORCEPROP 2 LASTPIN (-3350 1050) $PN DJ46
J 0
(-3340 1060);
DISPLAY 0.617021 (-3340 1060);
PAINT ORANGE (-3340 1060);
FORCEPROP 2 LASTPIN (-3350 1000) $PN DF49
J 0
(-3340 1010);
DISPLAY 0.617021 (-3340 1010);
PAINT ORANGE (-3340 1010);
FORCEPROP 2 LASTPIN (-3350 950) $PN DK51
J 0
(-3340 960);
DISPLAY 0.617021 (-3340 960);
PAINT ORANGE (-3340 960);
FORCEPROP 2 LASTPIN (-5050 950) $PN DG56
J 2
(-5060 960);
DISPLAY 0.617021 (-5060 960);
PAINT ORANGE (-5060 960);
FORCEPROP 2 LASTPIN (-5050 900) $PN DJ56
J 2
(-5060 910);
DISPLAY 0.617021 (-5060 910);
PAINT ORANGE (-5060 910);
FORCEPROP 2 LASTPIN (-5050 850) $PN DG54
J 2
(-5060 860);
DISPLAY 0.617021 (-5060 860);
PAINT ORANGE (-5060 860);
FORCEPROP 2 LASTPIN (-5050 800) $PN DJ54
J 2
(-5060 810);
DISPLAY 0.617021 (-5060 810);
PAINT ORANGE (-5060 810);
FORCEPROP 2 LASTPIN (-5050 750) $PN DF57
J 2
(-5060 760);
DISPLAY 0.617021 (-5060 760);
PAINT ORANGE (-5060 760);
FORCEPROP 2 LASTPIN (-5050 700) $PN DK57
J 2
(-5060 710);
DISPLAY 0.617021 (-5060 710);
PAINT ORANGE (-5060 710);
FORCEPROP 2 LASTPIN (-5050 650) $PN DF55
J 2
(-5060 660);
DISPLAY 0.617021 (-5060 660);
PAINT ORANGE (-5060 660);
FORCEPROP 2 LASTPIN (-5050 600) $PN DK55
J 2
(-5060 610);
DISPLAY 0.617021 (-5060 610);
PAINT ORANGE (-5060 610);
FORCEPROP 2 LASTPIN (-3350 1800) $PN DF63
J 0
(-3340 1810);
DISPLAY 0.617021 (-3340 1810);
PAINT ORANGE (-3340 1810);
FORCEPROP 2 LASTPIN (-3350 1750) $PN DK63
J 0
(-3340 1760);
DISPLAY 0.617021 (-3340 1760);
PAINT ORANGE (-3340 1760);
FORCEPROP 2 LASTPIN (-3350 1700) $PN DD63
J 0
(-3340 1710);
DISPLAY 0.617021 (-3340 1710);
PAINT ORANGE (-3340 1710);
FORCEPROP 2 LASTPIN (-3350 1650) $PN DG62
J 0
(-3340 1660);
DISPLAY 0.617021 (-3340 1660);
PAINT ORANGE (-3340 1660);
FORCEPROP 2 LASTPIN (-5050 500) $PN DF45
J 2
(-5060 510);
DISPLAY 0.617021 (-5060 510);
PAINT ORANGE (-5060 510);
FORCEPROP 2 LASTPIN (-3350 850) $PN DF61
J 0
(-3340 860);
DISPLAY 0.617021 (-3340 860);
PAINT ORANGE (-3340 860);
FORCEPROP 2 LASTPIN (-3350 800) $PN DA62
J 0
(-3340 810);
DISPLAY 0.617021 (-3340 810);
PAINT ORANGE (-3340 810);
FORCEPROP 2 LASTPIN (-3350 750) $PN DC56
J 0
(-3340 760);
DISPLAY 0.617021 (-3340 760);
PAINT ORANGE (-3340 760);
FORCEPROP 2 LASTPIN (-3350 700) $PN DJ52
J 0
(-3340 710);
DISPLAY 0.617021 (-3340 710);
PAINT ORANGE (-3340 710);
FORCEPROP 2 LASTPIN (-3350 550) $PN DD61
J 0
(-3340 560);
DISPLAY 0.617021 (-3340 560);
PAINT ORANGE (-3340 560);
FORCEPROP 2 LASTPIN (-3350 600) $PN DC62
J 0
(-3340 610);
DISPLAY 0.617021 (-3340 610);
PAINT ORANGE (-3340 610);
FORCEPROP 1 LAST PACK_TYPE BGA1
J 0
(-5000 4950);
PAINT SKYBLUE (-5000 4950);
DISPLAY INVISIBLE (-5000 4950);
FORCEPROP 2 LAST SEC_TYPE BGA1
J 0
(-5000 4950);
DISPLAY 1.021277 (-5000 4950);
PAINT ORANGE (-5000 4950);
DISPLAY INVISIBLE (-5000 4950);
FORCEPROP 2 LAST CDS_LIB chpset_lib
J 0
(-4200 2550);
PAINT ORANGE (-4200 2550);
DISPLAY INVISIBLE (-4200 2550);
FORCEPROP 2 LAST SEC 8
J 0
(-5000 4950);
DISPLAY 0.680851 (-5000 4950);
PAINT MONO (-5000 4950);
DISPLAY INVISIBLE (-5000 4950);
FORCEPROP 2 LAST CDS_LOCATION U2D1
J 0
(-5000 4900);
DISPLAY 0.617021 (-5000 4900);
PAINT AQUA (-5000 4900);
DISPLAY INVISIBLE (-5000 4900);
FORCEPROP 1 LAST PATH I172
J 0
(-4200 4850);
PAINT GREEN (-4200 4850);
DISPLAY INVISIBLE (-4200 4850);
FORCEADD TAP..6
(-5600 1300);
FORCEPROP 3 LASTPIN (-5550 1300) SIG_NAME M_M_ECC<5>
J 0
(-5540 1310);
DISPLAY 0.659574 (-5540 1310);
PAINT MONO (-5540 1310);
DISPLAY INVISIBLE (-5540 1310);
FORCEPROP 1 LASTPIN (-5550 1300) BN 5
J 0
(-5602 1308);
DISPLAY 0.617021 (-5602 1308);
PAINT GREEN (-5602 1308);
FORCEPROP 2 LAST CDS_LIB mstr_standard
J 0
(-5600 1300);
PAINT MONO (-5600 1300);
DISPLAY INVISIBLE (-5600 1300);
FORCEPROP 1 LAST BODY_TYPE PLUMBING
J 0
(-5600 1250);
DISPLAY 1.595745 (-5600 1250);
PAINT GREEN (-5600 1250);
DISPLAY INVISIBLE (-5600 1250);
FORCEPROP 1 LAST HDL_TAP TRUE
J 0
(-5275 1175);
DISPLAY 1.595745 (-5275 1175);
PAINT GREEN (-5275 1175);
DISPLAY INVISIBLE (-5275 1175);
FORCEPROP 1 LAST PATH I18
J 0
(-5602 1300);
DISPLAY 0.872340 (-5602 1300);
PAINT GREEN (-5602 1300);
DISPLAY INVISIBLE (-5602 1300);
FORCEADD TAP..6
(-5600 1350);
FORCEPROP 3 LASTPIN (-5550 1350) SIG_NAME M_M_ECC<6>
J 0
(-5540 1360);
DISPLAY 0.659574 (-5540 1360);
PAINT MONO (-5540 1360);
DISPLAY INVISIBLE (-5540 1360);
FORCEPROP 1 LASTPIN (-5550 1350) BN 6
J 0
(-5602 1358);
DISPLAY 0.617021 (-5602 1358);
PAINT GREEN (-5602 1358);
FORCEPROP 2 LAST CDS_LIB mstr_standard
J 0
(-5600 1350);
PAINT MONO (-5600 1350);
DISPLAY INVISIBLE (-5600 1350);
FORCEPROP 1 LAST BODY_TYPE PLUMBING
J 0
(-5600 1300);
DISPLAY 1.595745 (-5600 1300);
PAINT GREEN (-5600 1300);
DISPLAY INVISIBLE (-5600 1300);
FORCEPROP 1 LAST HDL_TAP TRUE
J 0
(-5275 1225);
DISPLAY 1.595745 (-5275 1225);
PAINT GREEN (-5275 1225);
DISPLAY INVISIBLE (-5275 1225);
FORCEPROP 1 LAST PATH I19
J 0
(-5602 1350);
DISPLAY 0.872340 (-5602 1350);
PAINT GREEN (-5602 1350);
DISPLAY INVISIBLE (-5602 1350);
FORCEADD OFFPAGE..5
(-6450 800);
FORCEPROP 2 LAST $XR0 87 
J 0
(-6674 800);
DISPLAY 0.638298 (-6674 800);
PAINT MONO (-6674 800);
FORCEPROP 2 LAST $XR1 88 
J 0
(-6764 800);
DISPLAY 0.638298 (-6764 800);
PAINT MONO (-6764 800);
FORCEPROP 2 LAST CDS_LIB mstr_standard
J 0
(-6450 800);
PAINT MONO (-6450 800);
DISPLAY INVISIBLE (-6450 800);
FORCEPROP 1 LAST OFFPAGE TRUE
J 0
(-6125 675);
DISPLAY 1.170213 (-6125 675);
PAINT GREEN (-6125 675);
DISPLAY INVISIBLE (-6125 675);
FORCEPROP 1 LAST COMMENT_BODY TRUE
J 0
(-6350 725);
DISPLAY 1.170213 (-6350 725);
PAINT GREEN (-6350 725);
DISPLAY INVISIBLE (-6350 725);
FORCEPROP 2 LAST PATH I2
J 0
(-6400 875);
DISPLAY 1.021277 (-6400 875);
PAINT ORANGE (-6400 875);
DISPLAY INVISIBLE (-6400 875);
FORCEADD TAP..6
(-5600 1400);
FORCEPROP 3 LASTPIN (-5550 1400) SIG_NAME M_M_ECC<7>
J 0
(-5540 1410);
DISPLAY 0.659574 (-5540 1410);
PAINT MONO (-5540 1410);
DISPLAY INVISIBLE (-5540 1410);
FORCEPROP 1 LASTPIN (-5550 1400) BN 7
J 0
(-5602 1408);
DISPLAY 0.617021 (-5602 1408);
PAINT GREEN (-5602 1408);
FORCEPROP 2 LAST CDS_LIB mstr_standard
J 0
(-5600 1400);
PAINT MONO (-5600 1400);
DISPLAY INVISIBLE (-5600 1400);
FORCEPROP 1 LAST BODY_TYPE PLUMBING
J 0
(-5600 1350);
DISPLAY 1.595745 (-5600 1350);
PAINT GREEN (-5600 1350);
DISPLAY INVISIBLE (-5600 1350);
FORCEPROP 1 LAST HDL_TAP TRUE
J 0
(-5275 1275);
DISPLAY 1.595745 (-5275 1275);
PAINT GREEN (-5275 1275);
DISPLAY INVISIBLE (-5275 1275);
FORCEPROP 1 LAST PATH I20
J 0
(-5602 1400);
DISPLAY 0.872340 (-5602 1400);
PAINT GREEN (-5602 1400);
DISPLAY INVISIBLE (-5602 1400);
FORCEADD TAP..6
(-5600 1500);
FORCEPROP 3 LASTPIN (-5550 1500) SIG_NAME M_M_DQ<0>
J 0
(-5540 1510);
DISPLAY 0.659574 (-5540 1510);
PAINT MONO (-5540 1510);
DISPLAY INVISIBLE (-5540 1510);
FORCEPROP 1 LASTPIN (-5550 1500) BN 0
J 0
(-5602 1508);
DISPLAY 0.617021 (-5602 1508);
PAINT GREEN (-5602 1508);
FORCEPROP 2 LAST CDS_LIB mstr_standard
J 0
(-5600 1500);
PAINT MONO (-5600 1500);
DISPLAY INVISIBLE (-5600 1500);
FORCEPROP 1 LAST BODY_TYPE PLUMBING
J 0
(-5600 1450);
DISPLAY 1.595745 (-5600 1450);
PAINT GREEN (-5600 1450);
DISPLAY INVISIBLE (-5600 1450);
FORCEPROP 1 LAST HDL_TAP TRUE
J 0
(-5275 1375);
DISPLAY 1.595745 (-5275 1375);
PAINT GREEN (-5275 1375);
DISPLAY INVISIBLE (-5275 1375);
FORCEPROP 1 LAST PATH I21
J 0
(-5602 1500);
DISPLAY 0.872340 (-5602 1500);
PAINT GREEN (-5602 1500);
DISPLAY INVISIBLE (-5602 1500);
FORCEADD TAP..6
(-5600 1550);
FORCEPROP 3 LASTPIN (-5550 1550) SIG_NAME M_M_DQ<1>
J 0
(-5540 1560);
DISPLAY 0.659574 (-5540 1560);
PAINT MONO (-5540 1560);
DISPLAY INVISIBLE (-5540 1560);
FORCEPROP 1 LASTPIN (-5550 1550) BN 1
J 0
(-5602 1558);
DISPLAY 0.617021 (-5602 1558);
PAINT GREEN (-5602 1558);
FORCEPROP 2 LAST CDS_LIB mstr_standard
J 0
(-5600 1550);
PAINT MONO (-5600 1550);
DISPLAY INVISIBLE (-5600 1550);
FORCEPROP 1 LAST BODY_TYPE PLUMBING
J 0
(-5600 1500);
DISPLAY 1.595745 (-5600 1500);
PAINT GREEN (-5600 1500);
DISPLAY INVISIBLE (-5600 1500);
FORCEPROP 1 LAST HDL_TAP TRUE
J 0
(-5275 1425);
DISPLAY 1.595745 (-5275 1425);
PAINT GREEN (-5275 1425);
DISPLAY INVISIBLE (-5275 1425);
FORCEPROP 1 LAST PATH I22
J 0
(-5602 1550);
DISPLAY 0.872340 (-5602 1550);
PAINT GREEN (-5602 1550);
DISPLAY INVISIBLE (-5602 1550);
FORCEADD TAP..6
(-5600 1600);
FORCEPROP 3 LASTPIN (-5550 1600) SIG_NAME M_M_DQ<2>
J 0
(-5540 1610);
DISPLAY 0.659574 (-5540 1610);
PAINT MONO (-5540 1610);
DISPLAY INVISIBLE (-5540 1610);
FORCEPROP 1 LASTPIN (-5550 1600) BN 2
J 0
(-5602 1608);
DISPLAY 0.617021 (-5602 1608);
PAINT GREEN (-5602 1608);
FORCEPROP 2 LAST CDS_LIB mstr_standard
J 0
(-5600 1600);
PAINT MONO (-5600 1600);
DISPLAY INVISIBLE (-5600 1600);
FORCEPROP 1 LAST BODY_TYPE PLUMBING
J 0
(-5600 1550);
DISPLAY 1.595745 (-5600 1550);
PAINT GREEN (-5600 1550);
DISPLAY INVISIBLE (-5600 1550);
FORCEPROP 1 LAST HDL_TAP TRUE
J 0
(-5275 1475);
DISPLAY 1.595745 (-5275 1475);
PAINT GREEN (-5275 1475);
DISPLAY INVISIBLE (-5275 1475);
FORCEPROP 1 LAST PATH I23
J 0
(-5602 1600);
DISPLAY 0.872340 (-5602 1600);
PAINT GREEN (-5602 1600);
DISPLAY INVISIBLE (-5602 1600);
FORCEADD TAP..6
(-5600 1650);
FORCEPROP 3 LASTPIN (-5550 1650) SIG_NAME M_M_DQ<3>
J 0
(-5540 1660);
DISPLAY 0.659574 (-5540 1660);
PAINT MONO (-5540 1660);
DISPLAY INVISIBLE (-5540 1660);
FORCEPROP 1 LASTPIN (-5550 1650) BN 3
J 0
(-5602 1658);
DISPLAY 0.617021 (-5602 1658);
PAINT GREEN (-5602 1658);
FORCEPROP 2 LAST CDS_LIB mstr_standard
J 0
(-5600 1650);
PAINT MONO (-5600 1650);
DISPLAY INVISIBLE (-5600 1650);
FORCEPROP 1 LAST BODY_TYPE PLUMBING
J 0
(-5600 1600);
DISPLAY 1.595745 (-5600 1600);
PAINT GREEN (-5600 1600);
DISPLAY INVISIBLE (-5600 1600);
FORCEPROP 1 LAST HDL_TAP TRUE
J 0
(-5275 1525);
DISPLAY 1.595745 (-5275 1525);
PAINT GREEN (-5275 1525);
DISPLAY INVISIBLE (-5275 1525);
FORCEPROP 1 LAST PATH I24
J 0
(-5602 1650);
DISPLAY 0.872340 (-5602 1650);
PAINT GREEN (-5602 1650);
DISPLAY INVISIBLE (-5602 1650);
FORCEADD TAP..6
(-5600 1700);
FORCEPROP 3 LASTPIN (-5550 1700) SIG_NAME M_M_DQ<4>
J 0
(-5540 1710);
DISPLAY 0.659574 (-5540 1710);
PAINT MONO (-5540 1710);
DISPLAY INVISIBLE (-5540 1710);
FORCEPROP 1 LASTPIN (-5550 1700) BN 4
J 0
(-5602 1708);
DISPLAY 0.617021 (-5602 1708);
PAINT GREEN (-5602 1708);
FORCEPROP 2 LAST CDS_LIB mstr_standard
J 0
(-5600 1700);
PAINT MONO (-5600 1700);
DISPLAY INVISIBLE (-5600 1700);
FORCEPROP 1 LAST BODY_TYPE PLUMBING
J 0
(-5600 1650);
DISPLAY 1.595745 (-5600 1650);
PAINT GREEN (-5600 1650);
DISPLAY INVISIBLE (-5600 1650);
FORCEPROP 1 LAST HDL_TAP TRUE
J 0
(-5275 1575);
DISPLAY 1.595745 (-5275 1575);
PAINT GREEN (-5275 1575);
DISPLAY INVISIBLE (-5275 1575);
FORCEPROP 1 LAST PATH I25
J 0
(-5602 1700);
DISPLAY 0.872340 (-5602 1700);
PAINT GREEN (-5602 1700);
DISPLAY INVISIBLE (-5602 1700);
FORCEADD TAP..6
(-5600 1750);
FORCEPROP 3 LASTPIN (-5550 1750) SIG_NAME M_M_DQ<5>
J 0
(-5540 1760);
DISPLAY 0.659574 (-5540 1760);
PAINT MONO (-5540 1760);
DISPLAY INVISIBLE (-5540 1760);
FORCEPROP 1 LASTPIN (-5550 1750) BN 5
J 0
(-5602 1758);
DISPLAY 0.617021 (-5602 1758);
PAINT GREEN (-5602 1758);
FORCEPROP 2 LAST CDS_LIB mstr_standard
J 0
(-5600 1750);
PAINT MONO (-5600 1750);
DISPLAY INVISIBLE (-5600 1750);
FORCEPROP 1 LAST BODY_TYPE PLUMBING
J 0
(-5600 1700);
DISPLAY 1.595745 (-5600 1700);
PAINT GREEN (-5600 1700);
DISPLAY INVISIBLE (-5600 1700);
FORCEPROP 1 LAST HDL_TAP TRUE
J 0
(-5275 1625);
DISPLAY 1.595745 (-5275 1625);
PAINT GREEN (-5275 1625);
DISPLAY INVISIBLE (-5275 1625);
FORCEPROP 1 LAST PATH I26
J 0
(-5602 1750);
DISPLAY 0.872340 (-5602 1750);
PAINT GREEN (-5602 1750);
DISPLAY INVISIBLE (-5602 1750);
FORCEADD TAP..6
(-5600 1800);
FORCEPROP 3 LASTPIN (-5550 1800) SIG_NAME M_M_DQ<6>
J 0
(-5540 1810);
DISPLAY 0.659574 (-5540 1810);
PAINT MONO (-5540 1810);
DISPLAY INVISIBLE (-5540 1810);
FORCEPROP 1 LASTPIN (-5550 1800) BN 6
J 0
(-5602 1808);
DISPLAY 0.617021 (-5602 1808);
PAINT GREEN (-5602 1808);
FORCEPROP 2 LAST CDS_LIB mstr_standard
J 0
(-5600 1800);
PAINT MONO (-5600 1800);
DISPLAY INVISIBLE (-5600 1800);
FORCEPROP 1 LAST BODY_TYPE PLUMBING
J 0
(-5600 1750);
DISPLAY 1.595745 (-5600 1750);
PAINT GREEN (-5600 1750);
DISPLAY INVISIBLE (-5600 1750);
FORCEPROP 1 LAST HDL_TAP TRUE
J 0
(-5275 1675);
DISPLAY 1.595745 (-5275 1675);
PAINT GREEN (-5275 1675);
DISPLAY INVISIBLE (-5275 1675);
FORCEPROP 1 LAST PATH I27
J 0
(-5602 1800);
DISPLAY 0.872340 (-5602 1800);
PAINT GREEN (-5602 1800);
DISPLAY INVISIBLE (-5602 1800);
FORCEADD TAP..6
(-5600 1900);
FORCEPROP 3 LASTPIN (-5550 1900) SIG_NAME M_M_DQ<8>
J 0
(-5540 1910);
DISPLAY 0.659574 (-5540 1910);
PAINT MONO (-5540 1910);
DISPLAY INVISIBLE (-5540 1910);
FORCEPROP 1 LASTPIN (-5550 1900) BN 8
J 0
(-5602 1908);
DISPLAY 0.617021 (-5602 1908);
PAINT GREEN (-5602 1908);
FORCEPROP 2 LAST CDS_LIB mstr_standard
J 0
(-5600 1900);
PAINT MONO (-5600 1900);
DISPLAY INVISIBLE (-5600 1900);
FORCEPROP 1 LAST BODY_TYPE PLUMBING
J 0
(-5600 1850);
DISPLAY 1.595745 (-5600 1850);
PAINT GREEN (-5600 1850);
DISPLAY INVISIBLE (-5600 1850);
FORCEPROP 1 LAST HDL_TAP TRUE
J 0
(-5275 1775);
DISPLAY 1.595745 (-5275 1775);
PAINT GREEN (-5275 1775);
DISPLAY INVISIBLE (-5275 1775);
FORCEPROP 1 LAST PATH I28
J 0
(-5602 1900);
DISPLAY 0.872340 (-5602 1900);
PAINT GREEN (-5602 1900);
DISPLAY INVISIBLE (-5602 1900);
FORCEADD TAP..6
(-5600 1850);
FORCEPROP 3 LASTPIN (-5550 1850) SIG_NAME M_M_DQ<7>
J 0
(-5540 1860);
DISPLAY 0.659574 (-5540 1860);
PAINT MONO (-5540 1860);
DISPLAY INVISIBLE (-5540 1860);
FORCEPROP 1 LASTPIN (-5550 1850) BN 7
J 0
(-5602 1858);
DISPLAY 0.617021 (-5602 1858);
PAINT GREEN (-5602 1858);
FORCEPROP 2 LAST CDS_LIB mstr_standard
J 0
(-5600 1850);
PAINT MONO (-5600 1850);
DISPLAY INVISIBLE (-5600 1850);
FORCEPROP 1 LAST BODY_TYPE PLUMBING
J 0
(-5600 1800);
DISPLAY 1.595745 (-5600 1800);
PAINT GREEN (-5600 1800);
DISPLAY INVISIBLE (-5600 1800);
FORCEPROP 1 LAST HDL_TAP TRUE
J 0
(-5275 1725);
DISPLAY 1.595745 (-5275 1725);
PAINT GREEN (-5275 1725);
DISPLAY INVISIBLE (-5275 1725);
FORCEPROP 1 LAST PATH I29
J 0
(-5602 1850);
DISPLAY 0.872340 (-5602 1850);
PAINT GREEN (-5602 1850);
DISPLAY INVISIBLE (-5602 1850);
FORCEADD OFFPAGE..5
(-6450 1000);
FORCEPROP 2 LAST $XR0 87 
J 0
(-6674 1000);
DISPLAY 0.638298 (-6674 1000);
PAINT MONO (-6674 1000);
FORCEPROP 2 LAST $XR1 88 
J 0
(-6764 1000);
DISPLAY 0.638298 (-6764 1000);
PAINT MONO (-6764 1000);
FORCEPROP 2 LAST CDS_LIB mstr_standard
J 0
(-6450 1000);
PAINT MONO (-6450 1000);
DISPLAY INVISIBLE (-6450 1000);
FORCEPROP 1 LAST OFFPAGE TRUE
J 0
(-6125 875);
DISPLAY 1.170213 (-6125 875);
PAINT GREEN (-6125 875);
DISPLAY INVISIBLE (-6125 875);
FORCEPROP 1 LAST COMMENT_BODY TRUE
J 0
(-6350 925);
DISPLAY 1.170213 (-6350 925);
PAINT GREEN (-6350 925);
DISPLAY INVISIBLE (-6350 925);
FORCEPROP 2 LAST PATH I3
J 0
(-6400 1075);
DISPLAY 1.021277 (-6400 1075);
PAINT ORANGE (-6400 1075);
DISPLAY INVISIBLE (-6400 1075);
FORCEADD TAP..6
(-5600 1950);
FORCEPROP 3 LASTPIN (-5550 1950) SIG_NAME M_M_DQ<9>
J 0
(-5540 1960);
DISPLAY 0.659574 (-5540 1960);
PAINT MONO (-5540 1960);
DISPLAY INVISIBLE (-5540 1960);
FORCEPROP 1 LASTPIN (-5550 1950) BN 9
J 0
(-5602 1958);
DISPLAY 0.617021 (-5602 1958);
PAINT GREEN (-5602 1958);
FORCEPROP 2 LAST CDS_LIB mstr_standard
J 0
(-5600 1950);
PAINT MONO (-5600 1950);
DISPLAY INVISIBLE (-5600 1950);
FORCEPROP 1 LAST BODY_TYPE PLUMBING
J 0
(-5600 1900);
DISPLAY 1.595745 (-5600 1900);
PAINT GREEN (-5600 1900);
DISPLAY INVISIBLE (-5600 1900);
FORCEPROP 1 LAST HDL_TAP TRUE
J 0
(-5275 1825);
DISPLAY 1.595745 (-5275 1825);
PAINT GREEN (-5275 1825);
DISPLAY INVISIBLE (-5275 1825);
FORCEPROP 1 LAST PATH I31
J 0
(-5602 1950);
DISPLAY 0.872340 (-5602 1950);
PAINT GREEN (-5602 1950);
DISPLAY INVISIBLE (-5602 1950);
FORCEADD TAP..6
(-5600 2000);
FORCEPROP 3 LASTPIN (-5550 2000) SIG_NAME M_M_DQ<10>
J 0
(-5540 2010);
DISPLAY 0.659574 (-5540 2010);
PAINT MONO (-5540 2010);
DISPLAY INVISIBLE (-5540 2010);
FORCEPROP 1 LASTPIN (-5550 2000) BN 10
J 0
(-5602 2008);
DISPLAY 0.617021 (-5602 2008);
PAINT GREEN (-5602 2008);
FORCEPROP 2 LAST CDS_LIB mstr_standard
J 0
(-5600 2000);
PAINT MONO (-5600 2000);
DISPLAY INVISIBLE (-5600 2000);
FORCEPROP 1 LAST BODY_TYPE PLUMBING
J 0
(-5600 1950);
DISPLAY 1.595745 (-5600 1950);
PAINT GREEN (-5600 1950);
DISPLAY INVISIBLE (-5600 1950);
FORCEPROP 1 LAST HDL_TAP TRUE
J 0
(-5275 1875);
DISPLAY 1.595745 (-5275 1875);
PAINT GREEN (-5275 1875);
DISPLAY INVISIBLE (-5275 1875);
FORCEPROP 1 LAST PATH I32
J 0
(-5602 2000);
DISPLAY 0.872340 (-5602 2000);
PAINT GREEN (-5602 2000);
DISPLAY INVISIBLE (-5602 2000);
FORCEADD TAP..6
(-5600 2050);
FORCEPROP 3 LASTPIN (-5550 2050) SIG_NAME M_M_DQ<11>
J 0
(-5540 2060);
DISPLAY 0.659574 (-5540 2060);
PAINT MONO (-5540 2060);
DISPLAY INVISIBLE (-5540 2060);
FORCEPROP 1 LASTPIN (-5550 2050) BN 11
J 0
(-5602 2058);
DISPLAY 0.617021 (-5602 2058);
PAINT GREEN (-5602 2058);
FORCEPROP 2 LAST CDS_LIB mstr_standard
J 0
(-5600 2050);
PAINT MONO (-5600 2050);
DISPLAY INVISIBLE (-5600 2050);
FORCEPROP 1 LAST BODY_TYPE PLUMBING
J 0
(-5600 2000);
DISPLAY 1.595745 (-5600 2000);
PAINT GREEN (-5600 2000);
DISPLAY INVISIBLE (-5600 2000);
FORCEPROP 1 LAST HDL_TAP TRUE
J 0
(-5275 1925);
DISPLAY 1.595745 (-5275 1925);
PAINT GREEN (-5275 1925);
DISPLAY INVISIBLE (-5275 1925);
FORCEPROP 1 LAST PATH I33
J 0
(-5602 2050);
DISPLAY 0.872340 (-5602 2050);
PAINT GREEN (-5602 2050);
DISPLAY INVISIBLE (-5602 2050);
FORCEADD TAP..6
(-5600 2100);
FORCEPROP 3 LASTPIN (-5550 2100) SIG_NAME M_M_DQ<12>
J 0
(-5540 2110);
DISPLAY 0.659574 (-5540 2110);
PAINT MONO (-5540 2110);
DISPLAY INVISIBLE (-5540 2110);
FORCEPROP 1 LASTPIN (-5550 2100) BN 12
J 0
(-5602 2108);
DISPLAY 0.617021 (-5602 2108);
PAINT GREEN (-5602 2108);
FORCEPROP 2 LAST CDS_LIB mstr_standard
J 0
(-5600 2100);
PAINT MONO (-5600 2100);
DISPLAY INVISIBLE (-5600 2100);
FORCEPROP 1 LAST BODY_TYPE PLUMBING
J 0
(-5600 2050);
DISPLAY 1.595745 (-5600 2050);
PAINT GREEN (-5600 2050);
DISPLAY INVISIBLE (-5600 2050);
FORCEPROP 1 LAST HDL_TAP TRUE
J 0
(-5275 1975);
DISPLAY 1.595745 (-5275 1975);
PAINT GREEN (-5275 1975);
DISPLAY INVISIBLE (-5275 1975);
FORCEPROP 1 LAST PATH I34
J 0
(-5602 2100);
DISPLAY 0.872340 (-5602 2100);
PAINT GREEN (-5602 2100);
DISPLAY INVISIBLE (-5602 2100);
FORCEADD TAP..6
(-5600 2150);
FORCEPROP 3 LASTPIN (-5550 2150) SIG_NAME M_M_DQ<13>
J 0
(-5540 2160);
DISPLAY 0.659574 (-5540 2160);
PAINT MONO (-5540 2160);
DISPLAY INVISIBLE (-5540 2160);
FORCEPROP 1 LASTPIN (-5550 2150) BN 13
J 0
(-5602 2158);
DISPLAY 0.617021 (-5602 2158);
PAINT GREEN (-5602 2158);
FORCEPROP 2 LAST CDS_LIB mstr_standard
J 0
(-5600 2150);
PAINT MONO (-5600 2150);
DISPLAY INVISIBLE (-5600 2150);
FORCEPROP 1 LAST BODY_TYPE PLUMBING
J 0
(-5600 2100);
DISPLAY 1.595745 (-5600 2100);
PAINT GREEN (-5600 2100);
DISPLAY INVISIBLE (-5600 2100);
FORCEPROP 1 LAST HDL_TAP TRUE
J 0
(-5275 2025);
DISPLAY 1.595745 (-5275 2025);
PAINT GREEN (-5275 2025);
DISPLAY INVISIBLE (-5275 2025);
FORCEPROP 1 LAST PATH I35
J 0
(-5602 2150);
DISPLAY 0.872340 (-5602 2150);
PAINT GREEN (-5602 2150);
DISPLAY INVISIBLE (-5602 2150);
FORCEADD TAP..6
(-5600 2200);
FORCEPROP 3 LASTPIN (-5550 2200) SIG_NAME M_M_DQ<14>
J 0
(-5540 2210);
DISPLAY 0.659574 (-5540 2210);
PAINT MONO (-5540 2210);
DISPLAY INVISIBLE (-5540 2210);
FORCEPROP 1 LASTPIN (-5550 2200) BN 14
J 0
(-5602 2208);
DISPLAY 0.617021 (-5602 2208);
PAINT GREEN (-5602 2208);
FORCEPROP 2 LAST CDS_LIB mstr_standard
J 0
(-5600 2200);
PAINT MONO (-5600 2200);
DISPLAY INVISIBLE (-5600 2200);
FORCEPROP 1 LAST BODY_TYPE PLUMBING
J 0
(-5600 2150);
DISPLAY 1.595745 (-5600 2150);
PAINT GREEN (-5600 2150);
DISPLAY INVISIBLE (-5600 2150);
FORCEPROP 1 LAST HDL_TAP TRUE
J 0
(-5275 2075);
DISPLAY 1.595745 (-5275 2075);
PAINT GREEN (-5275 2075);
DISPLAY INVISIBLE (-5275 2075);
FORCEPROP 1 LAST PATH I36
J 0
(-5602 2200);
DISPLAY 0.872340 (-5602 2200);
PAINT GREEN (-5602 2200);
DISPLAY INVISIBLE (-5602 2200);
FORCEADD TAP..6
(-5600 2250);
FORCEPROP 3 LASTPIN (-5550 2250) SIG_NAME M_M_DQ<15>
J 0
(-5540 2260);
DISPLAY 0.659574 (-5540 2260);
PAINT MONO (-5540 2260);
DISPLAY INVISIBLE (-5540 2260);
FORCEPROP 1 LASTPIN (-5550 2250) BN 15
J 0
(-5602 2258);
DISPLAY 0.617021 (-5602 2258);
PAINT GREEN (-5602 2258);
FORCEPROP 2 LAST CDS_LIB mstr_standard
J 0
(-5600 2250);
PAINT MONO (-5600 2250);
DISPLAY INVISIBLE (-5600 2250);
FORCEPROP 1 LAST BODY_TYPE PLUMBING
J 0
(-5600 2200);
DISPLAY 1.595745 (-5600 2200);
PAINT GREEN (-5600 2200);
DISPLAY INVISIBLE (-5600 2200);
FORCEPROP 1 LAST HDL_TAP TRUE
J 0
(-5275 2125);
DISPLAY 1.595745 (-5275 2125);
PAINT GREEN (-5275 2125);
DISPLAY INVISIBLE (-5275 2125);
FORCEPROP 1 LAST PATH I37
J 0
(-5602 2250);
DISPLAY 0.872340 (-5602 2250);
PAINT GREEN (-5602 2250);
DISPLAY INVISIBLE (-5602 2250);
FORCEADD TAP..6
(-5600 2300);
FORCEPROP 3 LASTPIN (-5550 2300) SIG_NAME M_M_DQ<16>
J 0
(-5540 2310);
DISPLAY 0.659574 (-5540 2310);
PAINT MONO (-5540 2310);
DISPLAY INVISIBLE (-5540 2310);
FORCEPROP 1 LASTPIN (-5550 2300) BN 16
J 0
(-5602 2308);
DISPLAY 0.617021 (-5602 2308);
PAINT GREEN (-5602 2308);
FORCEPROP 2 LAST CDS_LIB mstr_standard
J 0
(-5600 2300);
PAINT MONO (-5600 2300);
DISPLAY INVISIBLE (-5600 2300);
FORCEPROP 1 LAST BODY_TYPE PLUMBING
J 0
(-5600 2250);
DISPLAY 1.595745 (-5600 2250);
PAINT GREEN (-5600 2250);
DISPLAY INVISIBLE (-5600 2250);
FORCEPROP 1 LAST HDL_TAP TRUE
J 0
(-5275 2175);
DISPLAY 1.595745 (-5275 2175);
PAINT GREEN (-5275 2175);
DISPLAY INVISIBLE (-5275 2175);
FORCEPROP 1 LAST PATH I38
J 0
(-5602 2300);
DISPLAY 0.872340 (-5602 2300);
PAINT GREEN (-5602 2300);
DISPLAY INVISIBLE (-5602 2300);
FORCEADD TAP..6
(-5600 2350);
FORCEPROP 3 LASTPIN (-5550 2350) SIG_NAME M_M_DQ<17>
J 0
(-5540 2360);
DISPLAY 0.659574 (-5540 2360);
PAINT MONO (-5540 2360);
DISPLAY INVISIBLE (-5540 2360);
FORCEPROP 1 LASTPIN (-5550 2350) BN 17
J 0
(-5602 2358);
DISPLAY 0.617021 (-5602 2358);
PAINT GREEN (-5602 2358);
FORCEPROP 2 LAST CDS_LIB mstr_standard
J 0
(-5600 2350);
PAINT MONO (-5600 2350);
DISPLAY INVISIBLE (-5600 2350);
FORCEPROP 1 LAST BODY_TYPE PLUMBING
J 0
(-5600 2300);
DISPLAY 1.595745 (-5600 2300);
PAINT GREEN (-5600 2300);
DISPLAY INVISIBLE (-5600 2300);
FORCEPROP 1 LAST HDL_TAP TRUE
J 0
(-5275 2225);
DISPLAY 1.595745 (-5275 2225);
PAINT GREEN (-5275 2225);
DISPLAY INVISIBLE (-5275 2225);
FORCEPROP 1 LAST PATH I39
J 0
(-5602 2350);
DISPLAY 0.872340 (-5602 2350);
PAINT GREEN (-5602 2350);
DISPLAY INVISIBLE (-5602 2350);
FORCEADD OFFPAGE..6
(-6450 1450);
FORCEPROP 2 LAST $XR0 87 
J 0
(-6699 1450);
DISPLAY 0.638298 (-6699 1450);
PAINT MONO (-6699 1450);
FORCEPROP 2 LAST $XR1 88 
J 0
(-6789 1450);
DISPLAY 0.638298 (-6789 1450);
PAINT MONO (-6789 1450);
FORCEPROP 2 LAST CDS_LIB mstr_standard
J 0
(-6450 1450);
PAINT MONO (-6450 1450);
DISPLAY INVISIBLE (-6450 1450);
FORCEPROP 1 LAST OFFPAGE TRUE
J 0
(-6125 1325);
DISPLAY 1.170213 (-6125 1325);
PAINT GREEN (-6125 1325);
DISPLAY INVISIBLE (-6125 1325);
FORCEPROP 1 LAST COMMENT_BODY TRUE
J 0
(-6350 1375);
DISPLAY 1.170213 (-6350 1375);
PAINT GREEN (-6350 1375);
DISPLAY INVISIBLE (-6350 1375);
FORCEPROP 2 LAST PATH I4
J 0
(-6400 1525);
DISPLAY 1.021277 (-6400 1525);
PAINT ORANGE (-6400 1525);
DISPLAY INVISIBLE (-6400 1525);
FORCEADD TAP..6
(-5600 2400);
FORCEPROP 3 LASTPIN (-5550 2400) SIG_NAME M_M_DQ<18>
J 0
(-5540 2410);
DISPLAY 0.659574 (-5540 2410);
PAINT MONO (-5540 2410);
DISPLAY INVISIBLE (-5540 2410);
FORCEPROP 1 LASTPIN (-5550 2400) BN 18
J 0
(-5602 2408);
DISPLAY 0.617021 (-5602 2408);
PAINT GREEN (-5602 2408);
FORCEPROP 2 LAST CDS_LIB mstr_standard
J 0
(-5600 2400);
PAINT MONO (-5600 2400);
DISPLAY INVISIBLE (-5600 2400);
FORCEPROP 1 LAST BODY_TYPE PLUMBING
J 0
(-5600 2350);
DISPLAY 1.595745 (-5600 2350);
PAINT GREEN (-5600 2350);
DISPLAY INVISIBLE (-5600 2350);
FORCEPROP 1 LAST HDL_TAP TRUE
J 0
(-5275 2275);
DISPLAY 1.595745 (-5275 2275);
PAINT GREEN (-5275 2275);
DISPLAY INVISIBLE (-5275 2275);
FORCEPROP 1 LAST PATH I40
J 0
(-5602 2400);
DISPLAY 0.872340 (-5602 2400);
PAINT GREEN (-5602 2400);
DISPLAY INVISIBLE (-5602 2400);
FORCEADD TAP..6
(-5600 2450);
FORCEPROP 3 LASTPIN (-5550 2450) SIG_NAME M_M_DQ<19>
J 0
(-5540 2460);
DISPLAY 0.659574 (-5540 2460);
PAINT MONO (-5540 2460);
DISPLAY INVISIBLE (-5540 2460);
FORCEPROP 1 LASTPIN (-5550 2450) BN 19
J 0
(-5602 2458);
DISPLAY 0.617021 (-5602 2458);
PAINT GREEN (-5602 2458);
FORCEPROP 2 LAST CDS_LIB mstr_standard
J 0
(-5600 2450);
PAINT MONO (-5600 2450);
DISPLAY INVISIBLE (-5600 2450);
FORCEPROP 1 LAST BODY_TYPE PLUMBING
J 0
(-5600 2400);
DISPLAY 1.595745 (-5600 2400);
PAINT GREEN (-5600 2400);
DISPLAY INVISIBLE (-5600 2400);
FORCEPROP 1 LAST HDL_TAP TRUE
J 0
(-5275 2325);
DISPLAY 1.595745 (-5275 2325);
PAINT GREEN (-5275 2325);
DISPLAY INVISIBLE (-5275 2325);
FORCEPROP 1 LAST PATH I41
J 0
(-5602 2450);
DISPLAY 0.872340 (-5602 2450);
PAINT GREEN (-5602 2450);
DISPLAY INVISIBLE (-5602 2450);
FORCEADD TAP..6
(-5600 2500);
FORCEPROP 3 LASTPIN (-5550 2500) SIG_NAME M_M_DQ<20>
J 0
(-5540 2510);
DISPLAY 0.659574 (-5540 2510);
PAINT MONO (-5540 2510);
DISPLAY INVISIBLE (-5540 2510);
FORCEPROP 1 LASTPIN (-5550 2500) BN 20
J 0
(-5602 2508);
DISPLAY 0.617021 (-5602 2508);
PAINT GREEN (-5602 2508);
FORCEPROP 2 LAST CDS_LIB mstr_standard
J 0
(-5600 2500);
PAINT MONO (-5600 2500);
DISPLAY INVISIBLE (-5600 2500);
FORCEPROP 1 LAST BODY_TYPE PLUMBING
J 0
(-5600 2450);
DISPLAY 1.595745 (-5600 2450);
PAINT GREEN (-5600 2450);
DISPLAY INVISIBLE (-5600 2450);
FORCEPROP 1 LAST HDL_TAP TRUE
J 0
(-5275 2375);
DISPLAY 1.595745 (-5275 2375);
PAINT GREEN (-5275 2375);
DISPLAY INVISIBLE (-5275 2375);
FORCEPROP 1 LAST PATH I42
J 0
(-5602 2500);
DISPLAY 0.872340 (-5602 2500);
PAINT GREEN (-5602 2500);
DISPLAY INVISIBLE (-5602 2500);
FORCEADD TAP..6
(-5600 2550);
FORCEPROP 3 LASTPIN (-5550 2550) SIG_NAME M_M_DQ<21>
J 0
(-5540 2560);
DISPLAY 0.659574 (-5540 2560);
PAINT MONO (-5540 2560);
DISPLAY INVISIBLE (-5540 2560);
FORCEPROP 1 LASTPIN (-5550 2550) BN 21
J 0
(-5602 2558);
DISPLAY 0.617021 (-5602 2558);
PAINT GREEN (-5602 2558);
FORCEPROP 2 LAST CDS_LIB mstr_standard
J 0
(-5600 2550);
PAINT MONO (-5600 2550);
DISPLAY INVISIBLE (-5600 2550);
FORCEPROP 1 LAST BODY_TYPE PLUMBING
J 0
(-5600 2500);
DISPLAY 1.595745 (-5600 2500);
PAINT GREEN (-5600 2500);
DISPLAY INVISIBLE (-5600 2500);
FORCEPROP 1 LAST HDL_TAP TRUE
J 0
(-5275 2425);
DISPLAY 1.595745 (-5275 2425);
PAINT GREEN (-5275 2425);
DISPLAY INVISIBLE (-5275 2425);
FORCEPROP 1 LAST PATH I43
J 0
(-5602 2550);
DISPLAY 0.872340 (-5602 2550);
PAINT GREEN (-5602 2550);
DISPLAY INVISIBLE (-5602 2550);
FORCEADD TAP..6
(-5600 2600);
FORCEPROP 3 LASTPIN (-5550 2600) SIG_NAME M_M_DQ<22>
J 0
(-5540 2610);
DISPLAY 0.659574 (-5540 2610);
PAINT MONO (-5540 2610);
DISPLAY INVISIBLE (-5540 2610);
FORCEPROP 1 LASTPIN (-5550 2600) BN 22
J 0
(-5602 2608);
DISPLAY 0.617021 (-5602 2608);
PAINT GREEN (-5602 2608);
FORCEPROP 2 LAST CDS_LIB mstr_standard
J 0
(-5600 2600);
PAINT MONO (-5600 2600);
DISPLAY INVISIBLE (-5600 2600);
FORCEPROP 1 LAST BODY_TYPE PLUMBING
J 0
(-5600 2550);
DISPLAY 1.595745 (-5600 2550);
PAINT GREEN (-5600 2550);
DISPLAY INVISIBLE (-5600 2550);
FORCEPROP 1 LAST HDL_TAP TRUE
J 0
(-5275 2475);
DISPLAY 1.595745 (-5275 2475);
PAINT GREEN (-5275 2475);
DISPLAY INVISIBLE (-5275 2475);
FORCEPROP 1 LAST PATH I44
J 0
(-5602 2600);
DISPLAY 0.872340 (-5602 2600);
PAINT GREEN (-5602 2600);
DISPLAY INVISIBLE (-5602 2600);
FORCEADD TAP..6
(-5600 2650);
FORCEPROP 3 LASTPIN (-5550 2650) SIG_NAME M_M_DQ<23>
J 0
(-5540 2660);
DISPLAY 0.659574 (-5540 2660);
PAINT MONO (-5540 2660);
DISPLAY INVISIBLE (-5540 2660);
FORCEPROP 1 LASTPIN (-5550 2650) BN 23
J 0
(-5602 2658);
DISPLAY 0.617021 (-5602 2658);
PAINT GREEN (-5602 2658);
FORCEPROP 2 LAST CDS_LIB mstr_standard
J 0
(-5600 2650);
PAINT MONO (-5600 2650);
DISPLAY INVISIBLE (-5600 2650);
FORCEPROP 1 LAST BODY_TYPE PLUMBING
J 0
(-5600 2600);
DISPLAY 1.595745 (-5600 2600);
PAINT GREEN (-5600 2600);
DISPLAY INVISIBLE (-5600 2600);
FORCEPROP 1 LAST HDL_TAP TRUE
J 0
(-5275 2525);
DISPLAY 1.595745 (-5275 2525);
PAINT GREEN (-5275 2525);
DISPLAY INVISIBLE (-5275 2525);
FORCEPROP 1 LAST PATH I45
J 0
(-5602 2650);
DISPLAY 0.872340 (-5602 2650);
PAINT GREEN (-5602 2650);
DISPLAY INVISIBLE (-5602 2650);
FORCEADD TAP..6
(-5600 2700);
FORCEPROP 3 LASTPIN (-5550 2700) SIG_NAME M_M_DQ<24>
J 0
(-5540 2710);
DISPLAY 0.659574 (-5540 2710);
PAINT MONO (-5540 2710);
DISPLAY INVISIBLE (-5540 2710);
FORCEPROP 1 LASTPIN (-5550 2700) BN 24
J 0
(-5602 2708);
DISPLAY 0.617021 (-5602 2708);
PAINT GREEN (-5602 2708);
FORCEPROP 2 LAST CDS_LIB mstr_standard
J 0
(-5600 2700);
PAINT MONO (-5600 2700);
DISPLAY INVISIBLE (-5600 2700);
FORCEPROP 1 LAST BODY_TYPE PLUMBING
J 0
(-5600 2650);
DISPLAY 1.595745 (-5600 2650);
PAINT GREEN (-5600 2650);
DISPLAY INVISIBLE (-5600 2650);
FORCEPROP 1 LAST HDL_TAP TRUE
J 0
(-5275 2575);
DISPLAY 1.595745 (-5275 2575);
PAINT GREEN (-5275 2575);
DISPLAY INVISIBLE (-5275 2575);
FORCEPROP 1 LAST PATH I46
J 0
(-5602 2700);
DISPLAY 0.872340 (-5602 2700);
PAINT GREEN (-5602 2700);
DISPLAY INVISIBLE (-5602 2700);
FORCEADD TAP..6
(-5600 2800);
FORCEPROP 3 LASTPIN (-5550 2800) SIG_NAME M_M_DQ<26>
J 0
(-5540 2810);
DISPLAY 0.659574 (-5540 2810);
PAINT MONO (-5540 2810);
DISPLAY INVISIBLE (-5540 2810);
FORCEPROP 1 LASTPIN (-5550 2800) BN 26
J 0
(-5602 2808);
DISPLAY 0.617021 (-5602 2808);
PAINT GREEN (-5602 2808);
FORCEPROP 2 LAST CDS_LIB mstr_standard
J 0
(-5600 2800);
PAINT MONO (-5600 2800);
DISPLAY INVISIBLE (-5600 2800);
FORCEPROP 1 LAST BODY_TYPE PLUMBING
J 0
(-5600 2750);
DISPLAY 1.595745 (-5600 2750);
PAINT GREEN (-5600 2750);
DISPLAY INVISIBLE (-5600 2750);
FORCEPROP 1 LAST HDL_TAP TRUE
J 0
(-5275 2675);
DISPLAY 1.595745 (-5275 2675);
PAINT GREEN (-5275 2675);
DISPLAY INVISIBLE (-5275 2675);
FORCEPROP 1 LAST PATH I47
J 0
(-5602 2800);
DISPLAY 0.872340 (-5602 2800);
PAINT GREEN (-5602 2800);
DISPLAY INVISIBLE (-5602 2800);
FORCEADD TAP..6
(-5600 2750);
FORCEPROP 3 LASTPIN (-5550 2750) SIG_NAME M_M_DQ<25>
J 0
(-5540 2760);
DISPLAY 0.659574 (-5540 2760);
PAINT MONO (-5540 2760);
DISPLAY INVISIBLE (-5540 2760);
FORCEPROP 1 LASTPIN (-5550 2750) BN 25
J 0
(-5602 2758);
DISPLAY 0.617021 (-5602 2758);
PAINT GREEN (-5602 2758);
FORCEPROP 2 LAST CDS_LIB mstr_standard
J 0
(-5600 2750);
PAINT MONO (-5600 2750);
DISPLAY INVISIBLE (-5600 2750);
FORCEPROP 1 LAST BODY_TYPE PLUMBING
J 0
(-5600 2700);
DISPLAY 1.595745 (-5600 2700);
PAINT GREEN (-5600 2700);
DISPLAY INVISIBLE (-5600 2700);
FORCEPROP 1 LAST HDL_TAP TRUE
J 0
(-5275 2625);
DISPLAY 1.595745 (-5275 2625);
PAINT GREEN (-5275 2625);
DISPLAY INVISIBLE (-5275 2625);
FORCEPROP 1 LAST PATH I48
J 0
(-5602 2750);
DISPLAY 0.872340 (-5602 2750);
PAINT GREEN (-5602 2750);
DISPLAY INVISIBLE (-5602 2750);
FORCEADD TAP..6
(-5600 2850);
FORCEPROP 3 LASTPIN (-5550 2850) SIG_NAME M_M_DQ<27>
J 0
(-5540 2860);
DISPLAY 0.659574 (-5540 2860);
PAINT MONO (-5540 2860);
DISPLAY INVISIBLE (-5540 2860);
FORCEPROP 1 LASTPIN (-5550 2850) BN 27
J 0
(-5602 2858);
DISPLAY 0.617021 (-5602 2858);
PAINT GREEN (-5602 2858);
FORCEPROP 2 LAST CDS_LIB mstr_standard
J 0
(-5600 2850);
PAINT MONO (-5600 2850);
DISPLAY INVISIBLE (-5600 2850);
FORCEPROP 1 LAST BODY_TYPE PLUMBING
J 0
(-5600 2800);
DISPLAY 1.595745 (-5600 2800);
PAINT GREEN (-5600 2800);
DISPLAY INVISIBLE (-5600 2800);
FORCEPROP 1 LAST HDL_TAP TRUE
J 0
(-5275 2725);
DISPLAY 1.595745 (-5275 2725);
PAINT GREEN (-5275 2725);
DISPLAY INVISIBLE (-5275 2725);
FORCEPROP 1 LAST PATH I49
J 0
(-5602 2850);
DISPLAY 0.872340 (-5602 2850);
PAINT GREEN (-5602 2850);
DISPLAY INVISIBLE (-5602 2850);
FORCEADD TAP..6
(-5600 600);
FORCEPROP 3 LASTPIN (-5550 600) SIG_NAME M_M_CLK_DN<0>
J 0
(-5540 610);
DISPLAY 0.659574 (-5540 610);
PAINT MONO (-5540 610);
DISPLAY INVISIBLE (-5540 610);
FORCEPROP 1 LASTPIN (-5550 600) BN 0
J 0
(-5602 608);
DISPLAY 0.617021 (-5602 608);
PAINT GREEN (-5602 608);
FORCEPROP 2 LAST CDS_LIB mstr_standard
J 0
(-5600 600);
PAINT MONO (-5600 600);
DISPLAY INVISIBLE (-5600 600);
FORCEPROP 1 LAST BODY_TYPE PLUMBING
J 0
(-5600 550);
DISPLAY 1.595745 (-5600 550);
PAINT GREEN (-5600 550);
DISPLAY INVISIBLE (-5600 550);
FORCEPROP 1 LAST HDL_TAP TRUE
J 0
(-5275 475);
DISPLAY 1.595745 (-5275 475);
PAINT GREEN (-5275 475);
DISPLAY INVISIBLE (-5275 475);
FORCEPROP 1 LAST PATH I5
J 0
(-5602 600);
DISPLAY 0.872340 (-5602 600);
PAINT GREEN (-5602 600);
DISPLAY INVISIBLE (-5602 600);
FORCEADD TAP..6
(-5600 2900);
FORCEPROP 3 LASTPIN (-5550 2900) SIG_NAME M_M_DQ<28>
J 0
(-5540 2910);
DISPLAY 0.659574 (-5540 2910);
PAINT MONO (-5540 2910);
DISPLAY INVISIBLE (-5540 2910);
FORCEPROP 1 LASTPIN (-5550 2900) BN 28
J 0
(-5602 2908);
DISPLAY 0.617021 (-5602 2908);
PAINT GREEN (-5602 2908);
FORCEPROP 2 LAST CDS_LIB mstr_standard
J 0
(-5600 2900);
PAINT MONO (-5600 2900);
DISPLAY INVISIBLE (-5600 2900);
FORCEPROP 1 LAST BODY_TYPE PLUMBING
J 0
(-5600 2850);
DISPLAY 1.595745 (-5600 2850);
PAINT GREEN (-5600 2850);
DISPLAY INVISIBLE (-5600 2850);
FORCEPROP 1 LAST HDL_TAP TRUE
J 0
(-5275 2775);
DISPLAY 1.595745 (-5275 2775);
PAINT GREEN (-5275 2775);
DISPLAY INVISIBLE (-5275 2775);
FORCEPROP 1 LAST PATH I50
J 0
(-5602 2900);
DISPLAY 0.872340 (-5602 2900);
PAINT GREEN (-5602 2900);
DISPLAY INVISIBLE (-5602 2900);
FORCEADD TAP..6
(-5600 2950);
FORCEPROP 3 LASTPIN (-5550 2950) SIG_NAME M_M_DQ<29>
J 0
(-5540 2960);
DISPLAY 0.659574 (-5540 2960);
PAINT MONO (-5540 2960);
DISPLAY INVISIBLE (-5540 2960);
FORCEPROP 1 LASTPIN (-5550 2950) BN 29
J 0
(-5602 2958);
DISPLAY 0.617021 (-5602 2958);
PAINT GREEN (-5602 2958);
FORCEPROP 2 LAST CDS_LIB mstr_standard
J 0
(-5600 2950);
PAINT MONO (-5600 2950);
DISPLAY INVISIBLE (-5600 2950);
FORCEPROP 1 LAST BODY_TYPE PLUMBING
J 0
(-5600 2900);
DISPLAY 1.595745 (-5600 2900);
PAINT GREEN (-5600 2900);
DISPLAY INVISIBLE (-5600 2900);
FORCEPROP 1 LAST HDL_TAP TRUE
J 0
(-5275 2825);
DISPLAY 1.595745 (-5275 2825);
PAINT GREEN (-5275 2825);
DISPLAY INVISIBLE (-5275 2825);
FORCEPROP 1 LAST PATH I51
J 0
(-5602 2950);
DISPLAY 0.872340 (-5602 2950);
PAINT GREEN (-5602 2950);
DISPLAY INVISIBLE (-5602 2950);
FORCEADD TAP..6
(-5600 3050);
FORCEPROP 3 LASTPIN (-5550 3050) SIG_NAME M_M_DQ<31>
J 0
(-5540 3060);
DISPLAY 0.659574 (-5540 3060);
PAINT MONO (-5540 3060);
DISPLAY INVISIBLE (-5540 3060);
FORCEPROP 1 LASTPIN (-5550 3050) BN 31
J 0
(-5602 3058);
DISPLAY 0.617021 (-5602 3058);
PAINT GREEN (-5602 3058);
FORCEPROP 2 LAST CDS_LIB mstr_standard
J 0
(-5600 3050);
PAINT MONO (-5600 3050);
DISPLAY INVISIBLE (-5600 3050);
FORCEPROP 1 LAST BODY_TYPE PLUMBING
J 0
(-5600 3000);
DISPLAY 1.595745 (-5600 3000);
PAINT GREEN (-5600 3000);
DISPLAY INVISIBLE (-5600 3000);
FORCEPROP 1 LAST HDL_TAP TRUE
J 0
(-5275 2925);
DISPLAY 1.595745 (-5275 2925);
PAINT GREEN (-5275 2925);
DISPLAY INVISIBLE (-5275 2925);
FORCEPROP 1 LAST PATH I52
J 0
(-5602 3050);
DISPLAY 0.872340 (-5602 3050);
PAINT GREEN (-5602 3050);
DISPLAY INVISIBLE (-5602 3050);
FORCEADD TAP..6
(-5600 3000);
FORCEPROP 3 LASTPIN (-5550 3000) SIG_NAME M_M_DQ<30>
J 0
(-5540 3010);
DISPLAY 0.659574 (-5540 3010);
PAINT MONO (-5540 3010);
DISPLAY INVISIBLE (-5540 3010);
FORCEPROP 1 LASTPIN (-5550 3000) BN 30
J 0
(-5602 3008);
DISPLAY 0.617021 (-5602 3008);
PAINT GREEN (-5602 3008);
FORCEPROP 2 LAST CDS_LIB mstr_standard
J 0
(-5600 3000);
PAINT MONO (-5600 3000);
DISPLAY INVISIBLE (-5600 3000);
FORCEPROP 1 LAST BODY_TYPE PLUMBING
J 0
(-5600 2950);
DISPLAY 1.595745 (-5600 2950);
PAINT GREEN (-5600 2950);
DISPLAY INVISIBLE (-5600 2950);
FORCEPROP 1 LAST HDL_TAP TRUE
J 0
(-5275 2875);
DISPLAY 1.595745 (-5275 2875);
PAINT GREEN (-5275 2875);
DISPLAY INVISIBLE (-5275 2875);
FORCEPROP 1 LAST PATH I53
J 0
(-5602 3000);
DISPLAY 0.872340 (-5602 3000);
PAINT GREEN (-5602 3000);
DISPLAY INVISIBLE (-5602 3000);
FORCEADD TAP..6
(-5600 3100);
FORCEPROP 3 LASTPIN (-5550 3100) SIG_NAME M_M_DQ<32>
J 0
(-5540 3110);
DISPLAY 0.659574 (-5540 3110);
PAINT MONO (-5540 3110);
DISPLAY INVISIBLE (-5540 3110);
FORCEPROP 1 LASTPIN (-5550 3100) BN 32
J 0
(-5602 3108);
DISPLAY 0.617021 (-5602 3108);
PAINT GREEN (-5602 3108);
FORCEPROP 2 LAST CDS_LIB mstr_standard
J 0
(-5600 3100);
PAINT MONO (-5600 3100);
DISPLAY INVISIBLE (-5600 3100);
FORCEPROP 1 LAST BODY_TYPE PLUMBING
J 0
(-5600 3050);
DISPLAY 1.595745 (-5600 3050);
PAINT GREEN (-5600 3050);
DISPLAY INVISIBLE (-5600 3050);
FORCEPROP 1 LAST HDL_TAP TRUE
J 0
(-5275 2975);
DISPLAY 1.595745 (-5275 2975);
PAINT GREEN (-5275 2975);
DISPLAY INVISIBLE (-5275 2975);
FORCEPROP 1 LAST PATH I54
J 0
(-5602 3100);
DISPLAY 0.872340 (-5602 3100);
PAINT GREEN (-5602 3100);
DISPLAY INVISIBLE (-5602 3100);
FORCEADD TAP..6
(-5600 3150);
FORCEPROP 3 LASTPIN (-5550 3150) SIG_NAME M_M_DQ<33>
J 0
(-5540 3160);
DISPLAY 0.659574 (-5540 3160);
PAINT MONO (-5540 3160);
DISPLAY INVISIBLE (-5540 3160);
FORCEPROP 1 LASTPIN (-5550 3150) BN 33
J 0
(-5602 3158);
DISPLAY 0.617021 (-5602 3158);
PAINT GREEN (-5602 3158);
FORCEPROP 2 LAST CDS_LIB mstr_standard
J 0
(-5600 3150);
PAINT MONO (-5600 3150);
DISPLAY INVISIBLE (-5600 3150);
FORCEPROP 1 LAST BODY_TYPE PLUMBING
J 0
(-5600 3100);
DISPLAY 1.595745 (-5600 3100);
PAINT GREEN (-5600 3100);
DISPLAY INVISIBLE (-5600 3100);
FORCEPROP 1 LAST HDL_TAP TRUE
J 0
(-5275 3025);
DISPLAY 1.595745 (-5275 3025);
PAINT GREEN (-5275 3025);
DISPLAY INVISIBLE (-5275 3025);
FORCEPROP 1 LAST PATH I55
J 0
(-5602 3150);
DISPLAY 0.872340 (-5602 3150);
PAINT GREEN (-5602 3150);
DISPLAY INVISIBLE (-5602 3150);
FORCEADD TAP..6
(-5600 3200);
FORCEPROP 3 LASTPIN (-5550 3200) SIG_NAME M_M_DQ<34>
J 0
(-5540 3210);
DISPLAY 0.659574 (-5540 3210);
PAINT MONO (-5540 3210);
DISPLAY INVISIBLE (-5540 3210);
FORCEPROP 1 LASTPIN (-5550 3200) BN 34
J 0
(-5602 3208);
DISPLAY 0.617021 (-5602 3208);
PAINT GREEN (-5602 3208);
FORCEPROP 2 LAST CDS_LIB mstr_standard
J 0
(-5600 3200);
PAINT MONO (-5600 3200);
DISPLAY INVISIBLE (-5600 3200);
FORCEPROP 1 LAST BODY_TYPE PLUMBING
J 0
(-5600 3150);
DISPLAY 1.595745 (-5600 3150);
PAINT GREEN (-5600 3150);
DISPLAY INVISIBLE (-5600 3150);
FORCEPROP 1 LAST HDL_TAP TRUE
J 0
(-5275 3075);
DISPLAY 1.595745 (-5275 3075);
PAINT GREEN (-5275 3075);
DISPLAY INVISIBLE (-5275 3075);
FORCEPROP 1 LAST PATH I56
J 0
(-5602 3200);
DISPLAY 0.872340 (-5602 3200);
PAINT GREEN (-5602 3200);
DISPLAY INVISIBLE (-5602 3200);
FORCEADD TAP..6
(-5600 3300);
FORCEPROP 3 LASTPIN (-5550 3300) SIG_NAME M_M_DQ<36>
J 0
(-5540 3310);
DISPLAY 0.659574 (-5540 3310);
PAINT MONO (-5540 3310);
DISPLAY INVISIBLE (-5540 3310);
FORCEPROP 1 LASTPIN (-5550 3300) BN 36
J 0
(-5602 3308);
DISPLAY 0.617021 (-5602 3308);
PAINT GREEN (-5602 3308);
FORCEPROP 2 LAST CDS_LIB mstr_standard
J 0
(-5600 3300);
PAINT MONO (-5600 3300);
DISPLAY INVISIBLE (-5600 3300);
FORCEPROP 1 LAST BODY_TYPE PLUMBING
J 0
(-5600 3250);
DISPLAY 1.595745 (-5600 3250);
PAINT GREEN (-5600 3250);
DISPLAY INVISIBLE (-5600 3250);
FORCEPROP 1 LAST HDL_TAP TRUE
J 0
(-5275 3175);
DISPLAY 1.595745 (-5275 3175);
PAINT GREEN (-5275 3175);
DISPLAY INVISIBLE (-5275 3175);
FORCEPROP 1 LAST PATH I57
J 0
(-5602 3300);
DISPLAY 0.872340 (-5602 3300);
PAINT GREEN (-5602 3300);
DISPLAY INVISIBLE (-5602 3300);
FORCEADD TAP..6
(-5600 3250);
FORCEPROP 3 LASTPIN (-5550 3250) SIG_NAME M_M_DQ<35>
J 0
(-5540 3260);
DISPLAY 0.659574 (-5540 3260);
PAINT MONO (-5540 3260);
DISPLAY INVISIBLE (-5540 3260);
FORCEPROP 1 LASTPIN (-5550 3250) BN 35
J 0
(-5602 3258);
DISPLAY 0.617021 (-5602 3258);
PAINT GREEN (-5602 3258);
FORCEPROP 2 LAST CDS_LIB mstr_standard
J 0
(-5600 3250);
PAINT MONO (-5600 3250);
DISPLAY INVISIBLE (-5600 3250);
FORCEPROP 1 LAST BODY_TYPE PLUMBING
J 0
(-5600 3200);
DISPLAY 1.595745 (-5600 3200);
PAINT GREEN (-5600 3200);
DISPLAY INVISIBLE (-5600 3200);
FORCEPROP 1 LAST HDL_TAP TRUE
J 0
(-5275 3125);
DISPLAY 1.595745 (-5275 3125);
PAINT GREEN (-5275 3125);
DISPLAY INVISIBLE (-5275 3125);
FORCEPROP 1 LAST PATH I58
J 0
(-5602 3250);
DISPLAY 0.872340 (-5602 3250);
PAINT GREEN (-5602 3250);
DISPLAY INVISIBLE (-5602 3250);
FORCEADD TAP..6
(-5600 3350);
FORCEPROP 3 LASTPIN (-5550 3350) SIG_NAME M_M_DQ<37>
J 0
(-5540 3360);
DISPLAY 0.659574 (-5540 3360);
PAINT MONO (-5540 3360);
DISPLAY INVISIBLE (-5540 3360);
FORCEPROP 1 LASTPIN (-5550 3350) BN 37
J 0
(-5602 3358);
DISPLAY 0.617021 (-5602 3358);
PAINT GREEN (-5602 3358);
FORCEPROP 2 LAST CDS_LIB mstr_standard
J 0
(-5600 3350);
PAINT MONO (-5600 3350);
DISPLAY INVISIBLE (-5600 3350);
FORCEPROP 1 LAST BODY_TYPE PLUMBING
J 0
(-5600 3300);
DISPLAY 1.595745 (-5600 3300);
PAINT GREEN (-5600 3300);
DISPLAY INVISIBLE (-5600 3300);
FORCEPROP 1 LAST HDL_TAP TRUE
J 0
(-5275 3225);
DISPLAY 1.595745 (-5275 3225);
PAINT GREEN (-5275 3225);
DISPLAY INVISIBLE (-5275 3225);
FORCEPROP 1 LAST PATH I59
J 0
(-5602 3350);
DISPLAY 0.872340 (-5602 3350);
PAINT GREEN (-5602 3350);
DISPLAY INVISIBLE (-5602 3350);
FORCEADD TAP..6
(-5600 650);
FORCEPROP 3 LASTPIN (-5550 650) SIG_NAME M_M_CLK_DN<1>
J 0
(-5540 660);
DISPLAY 0.659574 (-5540 660);
PAINT MONO (-5540 660);
DISPLAY INVISIBLE (-5540 660);
FORCEPROP 1 LASTPIN (-5550 650) BN 1
J 0
(-5602 658);
DISPLAY 0.617021 (-5602 658);
PAINT GREEN (-5602 658);
FORCEPROP 2 LAST CDS_LIB mstr_standard
J 0
(-5600 650);
PAINT MONO (-5600 650);
DISPLAY INVISIBLE (-5600 650);
FORCEPROP 1 LAST BODY_TYPE PLUMBING
J 0
(-5600 600);
DISPLAY 1.595745 (-5600 600);
PAINT GREEN (-5600 600);
DISPLAY INVISIBLE (-5600 600);
FORCEPROP 1 LAST HDL_TAP TRUE
J 0
(-5275 525);
DISPLAY 1.595745 (-5275 525);
PAINT GREEN (-5275 525);
DISPLAY INVISIBLE (-5275 525);
FORCEPROP 1 LAST PATH I6
J 0
(-5602 650);
DISPLAY 0.872340 (-5602 650);
PAINT GREEN (-5602 650);
DISPLAY INVISIBLE (-5602 650);
FORCEADD TAP..6
(-5600 3400);
FORCEPROP 3 LASTPIN (-5550 3400) SIG_NAME M_M_DQ<38>
J 0
(-5540 3410);
DISPLAY 0.659574 (-5540 3410);
PAINT MONO (-5540 3410);
DISPLAY INVISIBLE (-5540 3410);
FORCEPROP 1 LASTPIN (-5550 3400) BN 38
J 0
(-5602 3408);
DISPLAY 0.617021 (-5602 3408);
PAINT GREEN (-5602 3408);
FORCEPROP 2 LAST CDS_LIB mstr_standard
J 0
(-5600 3400);
PAINT MONO (-5600 3400);
DISPLAY INVISIBLE (-5600 3400);
FORCEPROP 1 LAST BODY_TYPE PLUMBING
J 0
(-5600 3350);
DISPLAY 1.595745 (-5600 3350);
PAINT GREEN (-5600 3350);
DISPLAY INVISIBLE (-5600 3350);
FORCEPROP 1 LAST HDL_TAP TRUE
J 0
(-5275 3275);
DISPLAY 1.595745 (-5275 3275);
PAINT GREEN (-5275 3275);
DISPLAY INVISIBLE (-5275 3275);
FORCEPROP 1 LAST PATH I60
J 0
(-5602 3400);
DISPLAY 0.872340 (-5602 3400);
PAINT GREEN (-5602 3400);
DISPLAY INVISIBLE (-5602 3400);
FORCEADD TAP..6
(-5600 3450);
FORCEPROP 3 LASTPIN (-5550 3450) SIG_NAME M_M_DQ<39>
J 0
(-5540 3460);
DISPLAY 0.659574 (-5540 3460);
PAINT MONO (-5540 3460);
DISPLAY INVISIBLE (-5540 3460);
FORCEPROP 1 LASTPIN (-5550 3450) BN 39
J 0
(-5602 3458);
DISPLAY 0.617021 (-5602 3458);
PAINT GREEN (-5602 3458);
FORCEPROP 2 LAST CDS_LIB mstr_standard
J 0
(-5600 3450);
PAINT MONO (-5600 3450);
DISPLAY INVISIBLE (-5600 3450);
FORCEPROP 1 LAST BODY_TYPE PLUMBING
J 0
(-5600 3400);
DISPLAY 1.595745 (-5600 3400);
PAINT GREEN (-5600 3400);
DISPLAY INVISIBLE (-5600 3400);
FORCEPROP 1 LAST HDL_TAP TRUE
J 0
(-5275 3325);
DISPLAY 1.595745 (-5275 3325);
PAINT GREEN (-5275 3325);
DISPLAY INVISIBLE (-5275 3325);
FORCEPROP 1 LAST PATH I61
J 0
(-5602 3450);
DISPLAY 0.872340 (-5602 3450);
PAINT GREEN (-5602 3450);
DISPLAY INVISIBLE (-5602 3450);
FORCEADD TAP..6
(-5600 3500);
FORCEPROP 3 LASTPIN (-5550 3500) SIG_NAME M_M_DQ<40>
J 0
(-5540 3510);
DISPLAY 0.659574 (-5540 3510);
PAINT MONO (-5540 3510);
DISPLAY INVISIBLE (-5540 3510);
FORCEPROP 1 LASTPIN (-5550 3500) BN 40
J 0
(-5602 3508);
DISPLAY 0.617021 (-5602 3508);
PAINT GREEN (-5602 3508);
FORCEPROP 2 LAST CDS_LIB mstr_standard
J 0
(-5600 3500);
PAINT MONO (-5600 3500);
DISPLAY INVISIBLE (-5600 3500);
FORCEPROP 1 LAST BODY_TYPE PLUMBING
J 0
(-5600 3450);
DISPLAY 1.595745 (-5600 3450);
PAINT GREEN (-5600 3450);
DISPLAY INVISIBLE (-5600 3450);
FORCEPROP 1 LAST HDL_TAP TRUE
J 0
(-5275 3375);
DISPLAY 1.595745 (-5275 3375);
PAINT GREEN (-5275 3375);
DISPLAY INVISIBLE (-5275 3375);
FORCEPROP 1 LAST PATH I62
J 0
(-5602 3500);
DISPLAY 0.872340 (-5602 3500);
PAINT GREEN (-5602 3500);
DISPLAY INVISIBLE (-5602 3500);
FORCEADD TAP..6
(-5600 3550);
FORCEPROP 3 LASTPIN (-5550 3550) SIG_NAME M_M_DQ<41>
J 0
(-5540 3560);
DISPLAY 0.659574 (-5540 3560);
PAINT MONO (-5540 3560);
DISPLAY INVISIBLE (-5540 3560);
FORCEPROP 1 LASTPIN (-5550 3550) BN 41
J 0
(-5602 3558);
DISPLAY 0.617021 (-5602 3558);
PAINT GREEN (-5602 3558);
FORCEPROP 2 LAST CDS_LIB mstr_standard
J 0
(-5600 3550);
PAINT MONO (-5600 3550);
DISPLAY INVISIBLE (-5600 3550);
FORCEPROP 1 LAST BODY_TYPE PLUMBING
J 0
(-5600 3500);
DISPLAY 1.595745 (-5600 3500);
PAINT GREEN (-5600 3500);
DISPLAY INVISIBLE (-5600 3500);
FORCEPROP 1 LAST HDL_TAP TRUE
J 0
(-5275 3425);
DISPLAY 1.595745 (-5275 3425);
PAINT GREEN (-5275 3425);
DISPLAY INVISIBLE (-5275 3425);
FORCEPROP 1 LAST PATH I63
J 0
(-5602 3550);
DISPLAY 0.872340 (-5602 3550);
PAINT GREEN (-5602 3550);
DISPLAY INVISIBLE (-5602 3550);
FORCEADD TAP..6
(-5600 3600);
FORCEPROP 3 LASTPIN (-5550 3600) SIG_NAME M_M_DQ<42>
J 0
(-5540 3610);
DISPLAY 0.659574 (-5540 3610);
PAINT MONO (-5540 3610);
DISPLAY INVISIBLE (-5540 3610);
FORCEPROP 1 LASTPIN (-5550 3600) BN 42
J 0
(-5602 3608);
DISPLAY 0.617021 (-5602 3608);
PAINT GREEN (-5602 3608);
FORCEPROP 2 LAST CDS_LIB mstr_standard
J 0
(-5600 3600);
PAINT MONO (-5600 3600);
DISPLAY INVISIBLE (-5600 3600);
FORCEPROP 1 LAST BODY_TYPE PLUMBING
J 0
(-5600 3550);
DISPLAY 1.595745 (-5600 3550);
PAINT GREEN (-5600 3550);
DISPLAY INVISIBLE (-5600 3550);
FORCEPROP 1 LAST HDL_TAP TRUE
J 0
(-5275 3475);
DISPLAY 1.595745 (-5275 3475);
PAINT GREEN (-5275 3475);
DISPLAY INVISIBLE (-5275 3475);
FORCEPROP 1 LAST PATH I64
J 0
(-5602 3600);
DISPLAY 0.872340 (-5602 3600);
PAINT GREEN (-5602 3600);
DISPLAY INVISIBLE (-5602 3600);
FORCEADD TAP..6
(-5600 3650);
FORCEPROP 3 LASTPIN (-5550 3650) SIG_NAME M_M_DQ<43>
J 0
(-5540 3660);
DISPLAY 0.659574 (-5540 3660);
PAINT MONO (-5540 3660);
DISPLAY INVISIBLE (-5540 3660);
FORCEPROP 1 LASTPIN (-5550 3650) BN 43
J 0
(-5602 3658);
DISPLAY 0.617021 (-5602 3658);
PAINT GREEN (-5602 3658);
FORCEPROP 2 LAST CDS_LIB mstr_standard
J 0
(-5600 3650);
PAINT MONO (-5600 3650);
DISPLAY INVISIBLE (-5600 3650);
FORCEPROP 1 LAST BODY_TYPE PLUMBING
J 0
(-5600 3600);
DISPLAY 1.595745 (-5600 3600);
PAINT GREEN (-5600 3600);
DISPLAY INVISIBLE (-5600 3600);
FORCEPROP 1 LAST HDL_TAP TRUE
J 0
(-5275 3525);
DISPLAY 1.595745 (-5275 3525);
PAINT GREEN (-5275 3525);
DISPLAY INVISIBLE (-5275 3525);
FORCEPROP 1 LAST PATH I65
J 0
(-5602 3650);
DISPLAY 0.872340 (-5602 3650);
PAINT GREEN (-5602 3650);
DISPLAY INVISIBLE (-5602 3650);
FORCEADD TAP..6
(-5600 3700);
FORCEPROP 3 LASTPIN (-5550 3700) SIG_NAME M_M_DQ<44>
J 0
(-5540 3710);
DISPLAY 0.659574 (-5540 3710);
PAINT MONO (-5540 3710);
DISPLAY INVISIBLE (-5540 3710);
FORCEPROP 1 LASTPIN (-5550 3700) BN 44
J 0
(-5602 3708);
DISPLAY 0.617021 (-5602 3708);
PAINT GREEN (-5602 3708);
FORCEPROP 2 LAST CDS_LIB mstr_standard
J 0
(-5600 3700);
PAINT MONO (-5600 3700);
DISPLAY INVISIBLE (-5600 3700);
FORCEPROP 1 LAST BODY_TYPE PLUMBING
J 0
(-5600 3650);
DISPLAY 1.595745 (-5600 3650);
PAINT GREEN (-5600 3650);
DISPLAY INVISIBLE (-5600 3650);
FORCEPROP 1 LAST HDL_TAP TRUE
J 0
(-5275 3575);
DISPLAY 1.595745 (-5275 3575);
PAINT GREEN (-5275 3575);
DISPLAY INVISIBLE (-5275 3575);
FORCEPROP 1 LAST PATH I66
J 0
(-5602 3700);
DISPLAY 0.872340 (-5602 3700);
PAINT GREEN (-5602 3700);
DISPLAY INVISIBLE (-5602 3700);
FORCEADD TAP..6
(-5600 3750);
FORCEPROP 3 LASTPIN (-5550 3750) SIG_NAME M_M_DQ<45>
J 0
(-5540 3760);
DISPLAY 0.659574 (-5540 3760);
PAINT MONO (-5540 3760);
DISPLAY INVISIBLE (-5540 3760);
FORCEPROP 1 LASTPIN (-5550 3750) BN 45
J 0
(-5602 3758);
DISPLAY 0.617021 (-5602 3758);
PAINT GREEN (-5602 3758);
FORCEPROP 2 LAST CDS_LIB mstr_standard
J 0
(-5600 3750);
PAINT MONO (-5600 3750);
DISPLAY INVISIBLE (-5600 3750);
FORCEPROP 1 LAST BODY_TYPE PLUMBING
J 0
(-5600 3700);
DISPLAY 1.595745 (-5600 3700);
PAINT GREEN (-5600 3700);
DISPLAY INVISIBLE (-5600 3700);
FORCEPROP 1 LAST HDL_TAP TRUE
J 0
(-5275 3625);
DISPLAY 1.595745 (-5275 3625);
PAINT GREEN (-5275 3625);
DISPLAY INVISIBLE (-5275 3625);
FORCEPROP 1 LAST PATH I67
J 0
(-5602 3750);
DISPLAY 0.872340 (-5602 3750);
PAINT GREEN (-5602 3750);
DISPLAY INVISIBLE (-5602 3750);
FORCEADD TAP..6
(-5600 3800);
FORCEPROP 3 LASTPIN (-5550 3800) SIG_NAME M_M_DQ<46>
J 0
(-5540 3810);
DISPLAY 0.659574 (-5540 3810);
PAINT MONO (-5540 3810);
DISPLAY INVISIBLE (-5540 3810);
FORCEPROP 1 LASTPIN (-5550 3800) BN 46
J 0
(-5602 3808);
DISPLAY 0.617021 (-5602 3808);
PAINT GREEN (-5602 3808);
FORCEPROP 2 LAST CDS_LIB mstr_standard
J 0
(-5600 3800);
PAINT MONO (-5600 3800);
DISPLAY INVISIBLE (-5600 3800);
FORCEPROP 1 LAST BODY_TYPE PLUMBING
J 0
(-5600 3750);
DISPLAY 1.595745 (-5600 3750);
PAINT GREEN (-5600 3750);
DISPLAY INVISIBLE (-5600 3750);
FORCEPROP 1 LAST HDL_TAP TRUE
J 0
(-5275 3675);
DISPLAY 1.595745 (-5275 3675);
PAINT GREEN (-5275 3675);
DISPLAY INVISIBLE (-5275 3675);
FORCEPROP 1 LAST PATH I68
J 0
(-5602 3800);
DISPLAY 0.872340 (-5602 3800);
PAINT GREEN (-5602 3800);
DISPLAY INVISIBLE (-5602 3800);
FORCEADD TAP..6
(-5600 3850);
FORCEPROP 3 LASTPIN (-5550 3850) SIG_NAME M_M_DQ<47>
J 0
(-5540 3860);
DISPLAY 0.659574 (-5540 3860);
PAINT MONO (-5540 3860);
DISPLAY INVISIBLE (-5540 3860);
FORCEPROP 1 LASTPIN (-5550 3850) BN 47
J 0
(-5602 3858);
DISPLAY 0.617021 (-5602 3858);
PAINT GREEN (-5602 3858);
FORCEPROP 2 LAST CDS_LIB mstr_standard
J 0
(-5600 3850);
PAINT MONO (-5600 3850);
DISPLAY INVISIBLE (-5600 3850);
FORCEPROP 1 LAST BODY_TYPE PLUMBING
J 0
(-5600 3800);
DISPLAY 1.595745 (-5600 3800);
PAINT GREEN (-5600 3800);
DISPLAY INVISIBLE (-5600 3800);
FORCEPROP 1 LAST HDL_TAP TRUE
J 0
(-5275 3725);
DISPLAY 1.595745 (-5275 3725);
PAINT GREEN (-5275 3725);
DISPLAY INVISIBLE (-5275 3725);
FORCEPROP 1 LAST PATH I69
J 0
(-5602 3850);
DISPLAY 0.872340 (-5602 3850);
PAINT GREEN (-5602 3850);
DISPLAY INVISIBLE (-5602 3850);
FORCEADD TAP..6
(-5600 750);
FORCEPROP 3 LASTPIN (-5550 750) SIG_NAME M_M_CLK_DN<3>
J 0
(-5540 760);
DISPLAY 0.659574 (-5540 760);
PAINT MONO (-5540 760);
DISPLAY INVISIBLE (-5540 760);
FORCEPROP 1 LASTPIN (-5550 750) BN 3
J 0
(-5602 758);
DISPLAY 0.617021 (-5602 758);
PAINT GREEN (-5602 758);
FORCEPROP 2 LAST CDS_LIB mstr_standard
J 0
(-5600 750);
PAINT MONO (-5600 750);
DISPLAY INVISIBLE (-5600 750);
FORCEPROP 1 LAST BODY_TYPE PLUMBING
J 0
(-5600 700);
DISPLAY 1.595745 (-5600 700);
PAINT GREEN (-5600 700);
DISPLAY INVISIBLE (-5600 700);
FORCEPROP 1 LAST HDL_TAP TRUE
J 0
(-5275 625);
DISPLAY 1.595745 (-5275 625);
PAINT GREEN (-5275 625);
DISPLAY INVISIBLE (-5275 625);
FORCEPROP 1 LAST PATH I7
J 0
(-5602 750);
DISPLAY 0.872340 (-5602 750);
PAINT GREEN (-5602 750);
DISPLAY INVISIBLE (-5602 750);
FORCEADD TAP..6
(-5600 3900);
FORCEPROP 3 LASTPIN (-5550 3900) SIG_NAME M_M_DQ<48>
J 0
(-5540 3910);
DISPLAY 0.659574 (-5540 3910);
PAINT MONO (-5540 3910);
DISPLAY INVISIBLE (-5540 3910);
FORCEPROP 1 LASTPIN (-5550 3900) BN 48
J 0
(-5602 3908);
DISPLAY 0.617021 (-5602 3908);
PAINT GREEN (-5602 3908);
FORCEPROP 2 LAST CDS_LIB mstr_standard
J 0
(-5600 3900);
PAINT MONO (-5600 3900);
DISPLAY INVISIBLE (-5600 3900);
FORCEPROP 1 LAST BODY_TYPE PLUMBING
J 0
(-5600 3850);
DISPLAY 1.595745 (-5600 3850);
PAINT GREEN (-5600 3850);
DISPLAY INVISIBLE (-5600 3850);
FORCEPROP 1 LAST HDL_TAP TRUE
J 0
(-5275 3775);
DISPLAY 1.595745 (-5275 3775);
PAINT GREEN (-5275 3775);
DISPLAY INVISIBLE (-5275 3775);
FORCEPROP 1 LAST PATH I70
J 0
(-5602 3900);
DISPLAY 0.872340 (-5602 3900);
PAINT GREEN (-5602 3900);
DISPLAY INVISIBLE (-5602 3900);
FORCEADD TAP..6
(-5600 3950);
FORCEPROP 3 LASTPIN (-5550 3950) SIG_NAME M_M_DQ<49>
J 0
(-5540 3960);
DISPLAY 0.659574 (-5540 3960);
PAINT MONO (-5540 3960);
DISPLAY INVISIBLE (-5540 3960);
FORCEPROP 1 LASTPIN (-5550 3950) BN 49
J 0
(-5602 3958);
DISPLAY 0.617021 (-5602 3958);
PAINT GREEN (-5602 3958);
FORCEPROP 2 LAST CDS_LIB mstr_standard
J 0
(-5600 3950);
PAINT MONO (-5600 3950);
DISPLAY INVISIBLE (-5600 3950);
FORCEPROP 1 LAST BODY_TYPE PLUMBING
J 0
(-5600 3900);
DISPLAY 1.595745 (-5600 3900);
PAINT GREEN (-5600 3900);
DISPLAY INVISIBLE (-5600 3900);
FORCEPROP 1 LAST HDL_TAP TRUE
J 0
(-5275 3825);
DISPLAY 1.595745 (-5275 3825);
PAINT GREEN (-5275 3825);
DISPLAY INVISIBLE (-5275 3825);
FORCEPROP 1 LAST PATH I71
J 0
(-5602 3950);
DISPLAY 0.872340 (-5602 3950);
PAINT GREEN (-5602 3950);
DISPLAY INVISIBLE (-5602 3950);
FORCEADD OFFPAGE..6
(-6450 4775);
FORCEPROP 2 LAST $XR0 87 
J 0
(-6699 4775);
DISPLAY 0.638298 (-6699 4775);
PAINT MONO (-6699 4775);
FORCEPROP 2 LAST $XR1 88 
J 0
(-6789 4775);
DISPLAY 0.638298 (-6789 4775);
PAINT MONO (-6789 4775);
FORCEPROP 2 LAST CDS_LIB mstr_standard
J 0
(-6450 4775);
PAINT MONO (-6450 4775);
DISPLAY INVISIBLE (-6450 4775);
FORCEPROP 1 LAST OFFPAGE TRUE
J 0
(-6125 4650);
DISPLAY 1.170213 (-6125 4650);
PAINT GREEN (-6125 4650);
DISPLAY INVISIBLE (-6125 4650);
FORCEPROP 1 LAST COMMENT_BODY TRUE
J 0
(-6350 4700);
DISPLAY 1.170213 (-6350 4700);
PAINT GREEN (-6350 4700);
DISPLAY INVISIBLE (-6350 4700);
FORCEPROP 2 LAST PATH I72
J 0
(-6400 4850);
DISPLAY 1.021277 (-6400 4850);
PAINT ORANGE (-6400 4850);
DISPLAY INVISIBLE (-6400 4850);
FORCEADD TAP..6
(-5600 4000);
FORCEPROP 3 LASTPIN (-5550 4000) SIG_NAME M_M_DQ<50>
J 0
(-5540 4010);
DISPLAY 0.659574 (-5540 4010);
PAINT MONO (-5540 4010);
DISPLAY INVISIBLE (-5540 4010);
FORCEPROP 1 LASTPIN (-5550 4000) BN 50
J 0
(-5602 4008);
DISPLAY 0.617021 (-5602 4008);
PAINT GREEN (-5602 4008);
FORCEPROP 2 LAST CDS_LIB mstr_standard
J 0
(-5600 4000);
PAINT MONO (-5600 4000);
DISPLAY INVISIBLE (-5600 4000);
FORCEPROP 1 LAST BODY_TYPE PLUMBING
J 0
(-5600 3950);
DISPLAY 1.595745 (-5600 3950);
PAINT GREEN (-5600 3950);
DISPLAY INVISIBLE (-5600 3950);
FORCEPROP 1 LAST HDL_TAP TRUE
J 0
(-5275 3875);
DISPLAY 1.595745 (-5275 3875);
PAINT GREEN (-5275 3875);
DISPLAY INVISIBLE (-5275 3875);
FORCEPROP 1 LAST PATH I73
J 0
(-5602 4000);
DISPLAY 0.872340 (-5602 4000);
PAINT GREEN (-5602 4000);
DISPLAY INVISIBLE (-5602 4000);
FORCEADD TAP..6
(-5600 4050);
FORCEPROP 3 LASTPIN (-5550 4050) SIG_NAME M_M_DQ<51>
J 0
(-5540 4060);
DISPLAY 0.659574 (-5540 4060);
PAINT MONO (-5540 4060);
DISPLAY INVISIBLE (-5540 4060);
FORCEPROP 1 LASTPIN (-5550 4050) BN 51
J 0
(-5602 4058);
DISPLAY 0.617021 (-5602 4058);
PAINT GREEN (-5602 4058);
FORCEPROP 2 LAST CDS_LIB mstr_standard
J 0
(-5600 4050);
PAINT MONO (-5600 4050);
DISPLAY INVISIBLE (-5600 4050);
FORCEPROP 1 LAST BODY_TYPE PLUMBING
J 0
(-5600 4000);
DISPLAY 1.595745 (-5600 4000);
PAINT GREEN (-5600 4000);
DISPLAY INVISIBLE (-5600 4000);
FORCEPROP 1 LAST HDL_TAP TRUE
J 0
(-5275 3925);
DISPLAY 1.595745 (-5275 3925);
PAINT GREEN (-5275 3925);
DISPLAY INVISIBLE (-5275 3925);
FORCEPROP 1 LAST PATH I74
J 0
(-5602 4050);
DISPLAY 0.872340 (-5602 4050);
PAINT GREEN (-5602 4050);
DISPLAY INVISIBLE (-5602 4050);
FORCEADD TAP..6
(-5600 4100);
FORCEPROP 3 LASTPIN (-5550 4100) SIG_NAME M_M_DQ<52>
J 0
(-5540 4110);
DISPLAY 0.659574 (-5540 4110);
PAINT MONO (-5540 4110);
DISPLAY INVISIBLE (-5540 4110);
FORCEPROP 1 LASTPIN (-5550 4100) BN 52
J 0
(-5602 4108);
DISPLAY 0.617021 (-5602 4108);
PAINT GREEN (-5602 4108);
FORCEPROP 2 LAST CDS_LIB mstr_standard
J 0
(-5600 4100);
PAINT MONO (-5600 4100);
DISPLAY INVISIBLE (-5600 4100);
FORCEPROP 1 LAST BODY_TYPE PLUMBING
J 0
(-5600 4050);
DISPLAY 1.595745 (-5600 4050);
PAINT GREEN (-5600 4050);
DISPLAY INVISIBLE (-5600 4050);
FORCEPROP 1 LAST HDL_TAP TRUE
J 0
(-5275 3975);
DISPLAY 1.595745 (-5275 3975);
PAINT GREEN (-5275 3975);
DISPLAY INVISIBLE (-5275 3975);
FORCEPROP 1 LAST PATH I75
J 0
(-5602 4100);
DISPLAY 0.872340 (-5602 4100);
PAINT GREEN (-5602 4100);
DISPLAY INVISIBLE (-5602 4100);
FORCEADD TAP..6
(-5600 4150);
FORCEPROP 3 LASTPIN (-5550 4150) SIG_NAME M_M_DQ<53>
J 0
(-5540 4160);
DISPLAY 0.659574 (-5540 4160);
PAINT MONO (-5540 4160);
DISPLAY INVISIBLE (-5540 4160);
FORCEPROP 1 LASTPIN (-5550 4150) BN 53
J 0
(-5602 4158);
DISPLAY 0.617021 (-5602 4158);
PAINT GREEN (-5602 4158);
FORCEPROP 2 LAST CDS_LIB mstr_standard
J 0
(-5600 4150);
PAINT MONO (-5600 4150);
DISPLAY INVISIBLE (-5600 4150);
FORCEPROP 1 LAST BODY_TYPE PLUMBING
J 0
(-5600 4100);
DISPLAY 1.595745 (-5600 4100);
PAINT GREEN (-5600 4100);
DISPLAY INVISIBLE (-5600 4100);
FORCEPROP 1 LAST HDL_TAP TRUE
J 0
(-5275 4025);
DISPLAY 1.595745 (-5275 4025);
PAINT GREEN (-5275 4025);
DISPLAY INVISIBLE (-5275 4025);
FORCEPROP 1 LAST PATH I76
J 0
(-5602 4150);
DISPLAY 0.872340 (-5602 4150);
PAINT GREEN (-5602 4150);
DISPLAY INVISIBLE (-5602 4150);
FORCEADD TAP..6
(-5600 4200);
FORCEPROP 3 LASTPIN (-5550 4200) SIG_NAME M_M_DQ<54>
J 0
(-5540 4210);
DISPLAY 0.659574 (-5540 4210);
PAINT MONO (-5540 4210);
DISPLAY INVISIBLE (-5540 4210);
FORCEPROP 1 LASTPIN (-5550 4200) BN 54
J 0
(-5602 4208);
DISPLAY 0.617021 (-5602 4208);
PAINT GREEN (-5602 4208);
FORCEPROP 2 LAST CDS_LIB mstr_standard
J 0
(-5600 4200);
PAINT MONO (-5600 4200);
DISPLAY INVISIBLE (-5600 4200);
FORCEPROP 1 LAST BODY_TYPE PLUMBING
J 0
(-5600 4150);
DISPLAY 1.595745 (-5600 4150);
PAINT GREEN (-5600 4150);
DISPLAY INVISIBLE (-5600 4150);
FORCEPROP 1 LAST HDL_TAP TRUE
J 0
(-5275 4075);
DISPLAY 1.595745 (-5275 4075);
PAINT GREEN (-5275 4075);
DISPLAY INVISIBLE (-5275 4075);
FORCEPROP 1 LAST PATH I77
J 0
(-5602 4200);
DISPLAY 0.872340 (-5602 4200);
PAINT GREEN (-5602 4200);
DISPLAY INVISIBLE (-5602 4200);
FORCEADD TAP..6
(-5600 4250);
FORCEPROP 3 LASTPIN (-5550 4250) SIG_NAME M_M_DQ<55>
J 0
(-5540 4260);
DISPLAY 0.659574 (-5540 4260);
PAINT MONO (-5540 4260);
DISPLAY INVISIBLE (-5540 4260);
FORCEPROP 1 LASTPIN (-5550 4250) BN 55
J 0
(-5602 4258);
DISPLAY 0.617021 (-5602 4258);
PAINT GREEN (-5602 4258);
FORCEPROP 2 LAST CDS_LIB mstr_standard
J 0
(-5600 4250);
PAINT MONO (-5600 4250);
DISPLAY INVISIBLE (-5600 4250);
FORCEPROP 1 LAST BODY_TYPE PLUMBING
J 0
(-5600 4200);
DISPLAY 1.595745 (-5600 4200);
PAINT GREEN (-5600 4200);
DISPLAY INVISIBLE (-5600 4200);
FORCEPROP 1 LAST HDL_TAP TRUE
J 0
(-5275 4125);
DISPLAY 1.595745 (-5275 4125);
PAINT GREEN (-5275 4125);
DISPLAY INVISIBLE (-5275 4125);
FORCEPROP 1 LAST PATH I78
J 0
(-5602 4250);
DISPLAY 0.872340 (-5602 4250);
PAINT GREEN (-5602 4250);
DISPLAY INVISIBLE (-5602 4250);
FORCEADD TAP..6
(-5600 4300);
FORCEPROP 3 LASTPIN (-5550 4300) SIG_NAME M_M_DQ<56>
J 0
(-5540 4310);
DISPLAY 0.659574 (-5540 4310);
PAINT MONO (-5540 4310);
DISPLAY INVISIBLE (-5540 4310);
FORCEPROP 1 LASTPIN (-5550 4300) BN 56
J 0
(-5602 4308);
DISPLAY 0.617021 (-5602 4308);
PAINT GREEN (-5602 4308);
FORCEPROP 2 LAST CDS_LIB mstr_standard
J 0
(-5600 4300);
PAINT MONO (-5600 4300);
DISPLAY INVISIBLE (-5600 4300);
FORCEPROP 1 LAST BODY_TYPE PLUMBING
J 0
(-5600 4250);
DISPLAY 1.595745 (-5600 4250);
PAINT GREEN (-5600 4250);
DISPLAY INVISIBLE (-5600 4250);
FORCEPROP 1 LAST HDL_TAP TRUE
J 0
(-5275 4175);
DISPLAY 1.595745 (-5275 4175);
PAINT GREEN (-5275 4175);
DISPLAY INVISIBLE (-5275 4175);
FORCEPROP 1 LAST PATH I79
J 0
(-5602 4300);
DISPLAY 0.872340 (-5602 4300);
PAINT GREEN (-5602 4300);
DISPLAY INVISIBLE (-5602 4300);
FORCEADD TAP..6
(-5600 700);
FORCEPROP 3 LASTPIN (-5550 700) SIG_NAME M_M_CLK_DN<2>
J 0
(-5540 710);
DISPLAY 0.659574 (-5540 710);
PAINT MONO (-5540 710);
DISPLAY INVISIBLE (-5540 710);
FORCEPROP 1 LASTPIN (-5550 700) BN 2
J 0
(-5602 708);
DISPLAY 0.617021 (-5602 708);
PAINT GREEN (-5602 708);
FORCEPROP 2 LAST CDS_LIB mstr_standard
J 0
(-5600 700);
PAINT MONO (-5600 700);
DISPLAY INVISIBLE (-5600 700);
FORCEPROP 1 LAST BODY_TYPE PLUMBING
J 0
(-5600 650);
DISPLAY 1.595745 (-5600 650);
PAINT GREEN (-5600 650);
DISPLAY INVISIBLE (-5600 650);
FORCEPROP 1 LAST HDL_TAP TRUE
J 0
(-5275 575);
DISPLAY 1.595745 (-5275 575);
PAINT GREEN (-5275 575);
DISPLAY INVISIBLE (-5275 575);
FORCEPROP 1 LAST PATH I8
J 0
(-5602 700);
DISPLAY 0.872340 (-5602 700);
PAINT GREEN (-5602 700);
DISPLAY INVISIBLE (-5602 700);
FORCEADD TAP..6
(-5600 4350);
FORCEPROP 3 LASTPIN (-5550 4350) SIG_NAME M_M_DQ<57>
J 0
(-5540 4360);
DISPLAY 0.659574 (-5540 4360);
PAINT MONO (-5540 4360);
DISPLAY INVISIBLE (-5540 4360);
FORCEPROP 1 LASTPIN (-5550 4350) BN 57
J 0
(-5602 4358);
DISPLAY 0.617021 (-5602 4358);
PAINT GREEN (-5602 4358);
FORCEPROP 2 LAST CDS_LIB mstr_standard
J 0
(-5600 4350);
PAINT MONO (-5600 4350);
DISPLAY INVISIBLE (-5600 4350);
FORCEPROP 1 LAST BODY_TYPE PLUMBING
J 0
(-5600 4300);
DISPLAY 1.595745 (-5600 4300);
PAINT GREEN (-5600 4300);
DISPLAY INVISIBLE (-5600 4300);
FORCEPROP 1 LAST HDL_TAP TRUE
J 0
(-5275 4225);
DISPLAY 1.595745 (-5275 4225);
PAINT GREEN (-5275 4225);
DISPLAY INVISIBLE (-5275 4225);
FORCEPROP 1 LAST PATH I80
J 0
(-5602 4350);
DISPLAY 0.872340 (-5602 4350);
PAINT GREEN (-5602 4350);
DISPLAY INVISIBLE (-5602 4350);
FORCEADD TAP..6
(-5600 4400);
FORCEPROP 3 LASTPIN (-5550 4400) SIG_NAME M_M_DQ<58>
J 0
(-5540 4410);
DISPLAY 0.659574 (-5540 4410);
PAINT MONO (-5540 4410);
DISPLAY INVISIBLE (-5540 4410);
FORCEPROP 1 LASTPIN (-5550 4400) BN 58
J 0
(-5602 4408);
DISPLAY 0.617021 (-5602 4408);
PAINT GREEN (-5602 4408);
FORCEPROP 2 LAST CDS_LIB mstr_standard
J 0
(-5600 4400);
PAINT MONO (-5600 4400);
DISPLAY INVISIBLE (-5600 4400);
FORCEPROP 1 LAST BODY_TYPE PLUMBING
J 0
(-5600 4350);
DISPLAY 1.595745 (-5600 4350);
PAINT GREEN (-5600 4350);
DISPLAY INVISIBLE (-5600 4350);
FORCEPROP 1 LAST HDL_TAP TRUE
J 0
(-5275 4275);
DISPLAY 1.595745 (-5275 4275);
PAINT GREEN (-5275 4275);
DISPLAY INVISIBLE (-5275 4275);
FORCEPROP 1 LAST PATH I81
J 0
(-5602 4400);
DISPLAY 0.872340 (-5602 4400);
PAINT GREEN (-5602 4400);
DISPLAY INVISIBLE (-5602 4400);
FORCEADD TAP..6
(-5600 4450);
FORCEPROP 3 LASTPIN (-5550 4450) SIG_NAME M_M_DQ<59>
J 0
(-5540 4460);
DISPLAY 0.659574 (-5540 4460);
PAINT MONO (-5540 4460);
DISPLAY INVISIBLE (-5540 4460);
FORCEPROP 1 LASTPIN (-5550 4450) BN 59
J 0
(-5602 4458);
DISPLAY 0.617021 (-5602 4458);
PAINT GREEN (-5602 4458);
FORCEPROP 2 LAST CDS_LIB mstr_standard
J 0
(-5600 4450);
PAINT MONO (-5600 4450);
DISPLAY INVISIBLE (-5600 4450);
FORCEPROP 1 LAST BODY_TYPE PLUMBING
J 0
(-5600 4400);
DISPLAY 1.595745 (-5600 4400);
PAINT GREEN (-5600 4400);
DISPLAY INVISIBLE (-5600 4400);
FORCEPROP 1 LAST HDL_TAP TRUE
J 0
(-5275 4325);
DISPLAY 1.595745 (-5275 4325);
PAINT GREEN (-5275 4325);
DISPLAY INVISIBLE (-5275 4325);
FORCEPROP 1 LAST PATH I82
J 0
(-5602 4450);
DISPLAY 0.872340 (-5602 4450);
PAINT GREEN (-5602 4450);
DISPLAY INVISIBLE (-5602 4450);
FORCEADD TAP..6
(-5600 4500);
FORCEPROP 3 LASTPIN (-5550 4500) SIG_NAME M_M_DQ<60>
J 0
(-5540 4510);
DISPLAY 0.659574 (-5540 4510);
PAINT MONO (-5540 4510);
DISPLAY INVISIBLE (-5540 4510);
FORCEPROP 1 LASTPIN (-5550 4500) BN 60
J 0
(-5602 4508);
DISPLAY 0.617021 (-5602 4508);
PAINT GREEN (-5602 4508);
FORCEPROP 2 LAST CDS_LIB mstr_standard
J 0
(-5600 4500);
PAINT MONO (-5600 4500);
DISPLAY INVISIBLE (-5600 4500);
FORCEPROP 1 LAST BODY_TYPE PLUMBING
J 0
(-5600 4450);
DISPLAY 1.595745 (-5600 4450);
PAINT GREEN (-5600 4450);
DISPLAY INVISIBLE (-5600 4450);
FORCEPROP 1 LAST HDL_TAP TRUE
J 0
(-5275 4375);
DISPLAY 1.595745 (-5275 4375);
PAINT GREEN (-5275 4375);
DISPLAY INVISIBLE (-5275 4375);
FORCEPROP 1 LAST PATH I83
J 0
(-5602 4500);
DISPLAY 0.872340 (-5602 4500);
PAINT GREEN (-5602 4500);
DISPLAY INVISIBLE (-5602 4500);
FORCEADD TAP..6
(-5600 4550);
FORCEPROP 3 LASTPIN (-5550 4550) SIG_NAME M_M_DQ<61>
J 0
(-5540 4560);
DISPLAY 0.659574 (-5540 4560);
PAINT MONO (-5540 4560);
DISPLAY INVISIBLE (-5540 4560);
FORCEPROP 1 LASTPIN (-5550 4550) BN 61
J 0
(-5602 4558);
DISPLAY 0.617021 (-5602 4558);
PAINT GREEN (-5602 4558);
FORCEPROP 2 LAST CDS_LIB mstr_standard
J 0
(-5600 4550);
PAINT MONO (-5600 4550);
DISPLAY INVISIBLE (-5600 4550);
FORCEPROP 1 LAST BODY_TYPE PLUMBING
J 0
(-5600 4500);
DISPLAY 1.595745 (-5600 4500);
PAINT GREEN (-5600 4500);
DISPLAY INVISIBLE (-5600 4500);
FORCEPROP 1 LAST HDL_TAP TRUE
J 0
(-5275 4425);
DISPLAY 1.595745 (-5275 4425);
PAINT GREEN (-5275 4425);
DISPLAY INVISIBLE (-5275 4425);
FORCEPROP 1 LAST PATH I84
J 0
(-5602 4550);
DISPLAY 0.872340 (-5602 4550);
PAINT GREEN (-5602 4550);
DISPLAY INVISIBLE (-5602 4550);
FORCEADD TAP..6
(-5600 4600);
FORCEPROP 3 LASTPIN (-5550 4600) SIG_NAME M_M_DQ<62>
J 0
(-5540 4610);
DISPLAY 0.659574 (-5540 4610);
PAINT MONO (-5540 4610);
DISPLAY INVISIBLE (-5540 4610);
FORCEPROP 1 LASTPIN (-5550 4600) BN 62
J 0
(-5602 4608);
DISPLAY 0.617021 (-5602 4608);
PAINT GREEN (-5602 4608);
FORCEPROP 2 LAST CDS_LIB mstr_standard
J 0
(-5600 4600);
PAINT MONO (-5600 4600);
DISPLAY INVISIBLE (-5600 4600);
FORCEPROP 1 LAST BODY_TYPE PLUMBING
J 0
(-5600 4550);
DISPLAY 1.595745 (-5600 4550);
PAINT GREEN (-5600 4550);
DISPLAY INVISIBLE (-5600 4550);
FORCEPROP 1 LAST HDL_TAP TRUE
J 0
(-5275 4475);
DISPLAY 1.595745 (-5275 4475);
PAINT GREEN (-5275 4475);
DISPLAY INVISIBLE (-5275 4475);
FORCEPROP 1 LAST PATH I85
J 0
(-5602 4600);
DISPLAY 0.872340 (-5602 4600);
PAINT GREEN (-5602 4600);
DISPLAY INVISIBLE (-5602 4600);
FORCEADD TAP..6
(-5600 4650);
FORCEPROP 3 LASTPIN (-5550 4650) SIG_NAME M_M_DQ<63>
J 0
(-5540 4660);
DISPLAY 0.659574 (-5540 4660);
PAINT MONO (-5540 4660);
DISPLAY INVISIBLE (-5540 4660);
FORCEPROP 1 LASTPIN (-5550 4650) BN 63
J 0
(-5602 4658);
DISPLAY 0.617021 (-5602 4658);
PAINT GREEN (-5602 4658);
FORCEPROP 2 LAST CDS_LIB mstr_standard
J 0
(-5600 4650);
PAINT MONO (-5600 4650);
DISPLAY INVISIBLE (-5600 4650);
FORCEPROP 1 LAST BODY_TYPE PLUMBING
J 0
(-5600 4600);
DISPLAY 1.595745 (-5600 4600);
PAINT GREEN (-5600 4600);
DISPLAY INVISIBLE (-5600 4600);
FORCEPROP 1 LAST HDL_TAP TRUE
J 0
(-5275 4525);
DISPLAY 1.595745 (-5275 4525);
PAINT GREEN (-5275 4525);
DISPLAY INVISIBLE (-5275 4525);
FORCEPROP 1 LAST PATH I86
J 0
(-5602 4650);
DISPLAY 0.872340 (-5602 4650);
PAINT GREEN (-5602 4650);
DISPLAY INVISIBLE (-5602 4650);
FORCEADD TAP..6
R 2
(-2875 750);
FORCEPROP 3 LASTPIN (-2925 750) SIG_NAME M_M_BA<1>
J 0
(-2915 760);
DISPLAY 0.659574 (-2915 760);
PAINT MONO (-2915 760);
DISPLAY INVISIBLE (-2915 760);
FORCEPROP 1 LASTPIN (-2925 750) BN 1
J 2
(-2873 758);
DISPLAY 0.617021 (-2873 758);
PAINT GREEN (-2873 758);
FORCEPROP 2 LAST CDS_LIB mstr_standard
J 0
(-2875 750);
PAINT MONO (-2875 750);
DISPLAY INVISIBLE (-2875 750);
FORCEPROP 1 LAST BODY_TYPE PLUMBING
J 2
(-2875 700);
DISPLAY 1.595745 (-2875 700);
PAINT GREEN (-2875 700);
DISPLAY INVISIBLE (-2875 700);
FORCEPROP 1 LAST HDL_TAP TRUE
J 2
(-3200 625);
DISPLAY 1.595745 (-3200 625);
PAINT GREEN (-3200 625);
DISPLAY INVISIBLE (-3200 625);
FORCEPROP 1 LAST PATH I87
J 2
(-2873 750);
DISPLAY 0.872340 (-2873 750);
PAINT GREEN (-2873 750);
DISPLAY INVISIBLE (-2873 750);
FORCEADD TAP..6
R 2
(-2875 700);
FORCEPROP 3 LASTPIN (-2925 700) SIG_NAME M_M_BA<0>
J 0
(-2915 710);
DISPLAY 0.659574 (-2915 710);
PAINT MONO (-2915 710);
DISPLAY INVISIBLE (-2915 710);
FORCEPROP 1 LASTPIN (-2925 700) BN 0
J 2
(-2873 708);
DISPLAY 0.617021 (-2873 708);
PAINT GREEN (-2873 708);
FORCEPROP 2 LAST CDS_LIB mstr_standard
J 0
(-2875 700);
PAINT MONO (-2875 700);
DISPLAY INVISIBLE (-2875 700);
FORCEPROP 1 LAST BODY_TYPE PLUMBING
J 2
(-2875 650);
DISPLAY 1.595745 (-2875 650);
PAINT GREEN (-2875 650);
DISPLAY INVISIBLE (-2875 650);
FORCEPROP 1 LAST HDL_TAP TRUE
J 2
(-3200 575);
DISPLAY 1.595745 (-3200 575);
PAINT GREEN (-3200 575);
DISPLAY INVISIBLE (-3200 575);
FORCEPROP 1 LAST PATH I88
J 2
(-2873 700);
DISPLAY 0.872340 (-2873 700);
PAINT GREEN (-2873 700);
DISPLAY INVISIBLE (-2873 700);
FORCEADD TAP..6
R 2
(-2875 800);
FORCEPROP 3 LASTPIN (-2925 800) SIG_NAME M_M_BG<0>
J 0
(-2915 810);
DISPLAY 0.659574 (-2915 810);
PAINT MONO (-2915 810);
DISPLAY INVISIBLE (-2915 810);
FORCEPROP 1 LASTPIN (-2925 800) BN 0
J 2
(-2873 808);
DISPLAY 0.617021 (-2873 808);
PAINT GREEN (-2873 808);
FORCEPROP 2 LAST CDS_LIB mstr_standard
J 0
(-2875 800);
PAINT MONO (-2875 800);
DISPLAY INVISIBLE (-2875 800);
FORCEPROP 1 LAST BODY_TYPE PLUMBING
J 2
(-2875 750);
DISPLAY 1.595745 (-2875 750);
PAINT GREEN (-2875 750);
DISPLAY INVISIBLE (-2875 750);
FORCEPROP 1 LAST HDL_TAP TRUE
J 2
(-3200 675);
DISPLAY 1.595745 (-3200 675);
PAINT GREEN (-3200 675);
DISPLAY INVISIBLE (-3200 675);
FORCEPROP 1 LAST PATH I89
J 2
(-2873 800);
DISPLAY 0.872340 (-2873 800);
PAINT GREEN (-2873 800);
DISPLAY INVISIBLE (-2873 800);
FORCEADD TAP..6
(-5600 850);
FORCEPROP 3 LASTPIN (-5550 850) SIG_NAME M_M_CLK_DP<1>
J 0
(-5540 860);
DISPLAY 0.659574 (-5540 860);
PAINT MONO (-5540 860);
DISPLAY INVISIBLE (-5540 860);
FORCEPROP 1 LASTPIN (-5550 850) BN 1
J 0
(-5602 858);
DISPLAY 0.617021 (-5602 858);
PAINT GREEN (-5602 858);
FORCEPROP 2 LAST CDS_LIB mstr_standard
J 0
(-5600 850);
PAINT MONO (-5600 850);
DISPLAY INVISIBLE (-5600 850);
FORCEPROP 1 LAST BODY_TYPE PLUMBING
J 0
(-5600 800);
DISPLAY 1.595745 (-5600 800);
PAINT GREEN (-5600 800);
DISPLAY INVISIBLE (-5600 800);
FORCEPROP 1 LAST HDL_TAP TRUE
J 0
(-5275 725);
DISPLAY 1.595745 (-5275 725);
PAINT GREEN (-5275 725);
DISPLAY INVISIBLE (-5275 725);
FORCEPROP 1 LAST PATH I9
J 0
(-5602 850);
DISPLAY 0.872340 (-5602 850);
PAINT GREEN (-5602 850);
DISPLAY INVISIBLE (-5602 850);
FORCEADD TAP..6
R 2
(-2875 850);
FORCEPROP 3 LASTPIN (-2925 850) SIG_NAME M_M_BG<1>
J 0
(-2915 860);
DISPLAY 0.659574 (-2915 860);
PAINT MONO (-2915 860);
DISPLAY INVISIBLE (-2915 860);
FORCEPROP 1 LASTPIN (-2925 850) BN 1
J 2
(-2873 858);
DISPLAY 0.617021 (-2873 858);
PAINT GREEN (-2873 858);
FORCEPROP 2 LAST CDS_LIB mstr_standard
J 0
(-2875 850);
PAINT MONO (-2875 850);
DISPLAY INVISIBLE (-2875 850);
FORCEPROP 1 LAST BODY_TYPE PLUMBING
J 2
(-2875 800);
DISPLAY 1.595745 (-2875 800);
PAINT GREEN (-2875 800);
DISPLAY INVISIBLE (-2875 800);
FORCEPROP 1 LAST HDL_TAP TRUE
J 2
(-3200 725);
DISPLAY 1.595745 (-3200 725);
PAINT GREEN (-3200 725);
DISPLAY INVISIBLE (-3200 725);
FORCEPROP 1 LAST PATH I90
J 2
(-2873 850);
DISPLAY 0.872340 (-2873 850);
PAINT GREEN (-2873 850);
DISPLAY INVISIBLE (-2873 850);
FORCEADD TAP..6
R 2
(-2875 1050);
FORCEPROP 3 LASTPIN (-2925 1050) SIG_NAME M_M_CS_N<2>
J 0
(-2915 1060);
DISPLAY 0.659574 (-2915 1060);
PAINT MONO (-2915 1060);
DISPLAY INVISIBLE (-2915 1060);
FORCEPROP 1 LASTPIN (-2925 1050) BN 2
J 2
(-2873 1058);
DISPLAY 0.617021 (-2873 1058);
PAINT GREEN (-2873 1058);
FORCEPROP 2 LAST CDS_LIB mstr_standard
J 0
(-2875 1050);
PAINT MONO (-2875 1050);
DISPLAY INVISIBLE (-2875 1050);
FORCEPROP 1 LAST BODY_TYPE PLUMBING
J 2
(-2875 1000);
DISPLAY 1.595745 (-2875 1000);
PAINT GREEN (-2875 1000);
DISPLAY INVISIBLE (-2875 1000);
FORCEPROP 1 LAST HDL_TAP TRUE
J 2
(-3200 925);
DISPLAY 1.595745 (-3200 925);
PAINT GREEN (-3200 925);
DISPLAY INVISIBLE (-3200 925);
FORCEPROP 1 LAST PATH I91
J 2
(-2873 1050);
DISPLAY 0.872340 (-2873 1050);
PAINT GREEN (-2873 1050);
DISPLAY INVISIBLE (-2873 1050);
FORCEADD TAP..6
R 2
(-2875 1000);
FORCEPROP 3 LASTPIN (-2925 1000) SIG_NAME M_M_CS_N<1>
J 0
(-2915 1010);
DISPLAY 0.659574 (-2915 1010);
PAINT MONO (-2915 1010);
DISPLAY INVISIBLE (-2915 1010);
FORCEPROP 1 LASTPIN (-2925 1000) BN 1
J 2
(-2873 1008);
DISPLAY 0.617021 (-2873 1008);
PAINT GREEN (-2873 1008);
FORCEPROP 2 LAST CDS_LIB mstr_standard
J 0
(-2875 1000);
PAINT MONO (-2875 1000);
DISPLAY INVISIBLE (-2875 1000);
FORCEPROP 1 LAST BODY_TYPE PLUMBING
J 2
(-2875 950);
DISPLAY 1.595745 (-2875 950);
PAINT GREEN (-2875 950);
DISPLAY INVISIBLE (-2875 950);
FORCEPROP 1 LAST HDL_TAP TRUE
J 2
(-3200 875);
DISPLAY 1.595745 (-3200 875);
PAINT GREEN (-3200 875);
DISPLAY INVISIBLE (-3200 875);
FORCEPROP 1 LAST PATH I92
J 2
(-2873 1000);
DISPLAY 0.872340 (-2873 1000);
PAINT GREEN (-2873 1000);
DISPLAY INVISIBLE (-2873 1000);
FORCEADD TAP..6
R 2
(-2875 950);
FORCEPROP 3 LASTPIN (-2925 950) SIG_NAME M_M_CS_N<0>
J 0
(-2915 960);
DISPLAY 0.659574 (-2915 960);
PAINT MONO (-2915 960);
DISPLAY INVISIBLE (-2915 960);
FORCEPROP 1 LASTPIN (-2925 950) BN 0
J 2
(-2873 958);
DISPLAY 0.617021 (-2873 958);
PAINT GREEN (-2873 958);
FORCEPROP 2 LAST CDS_LIB mstr_standard
J 0
(-2875 950);
PAINT MONO (-2875 950);
DISPLAY INVISIBLE (-2875 950);
FORCEPROP 1 LAST BODY_TYPE PLUMBING
J 2
(-2875 900);
DISPLAY 1.595745 (-2875 900);
PAINT GREEN (-2875 900);
DISPLAY INVISIBLE (-2875 900);
FORCEPROP 1 LAST HDL_TAP TRUE
J 2
(-3200 825);
DISPLAY 1.595745 (-3200 825);
PAINT GREEN (-3200 825);
DISPLAY INVISIBLE (-3200 825);
FORCEPROP 1 LAST PATH I93
J 2
(-2873 950);
DISPLAY 0.872340 (-2873 950);
PAINT GREEN (-2873 950);
DISPLAY INVISIBLE (-2873 950);
FORCEADD TAP..6
R 2
(-2875 1150);
FORCEPROP 3 LASTPIN (-2925 1150) SIG_NAME M_M_CS_N<4>
J 0
(-2915 1160);
DISPLAY 0.659574 (-2915 1160);
PAINT MONO (-2915 1160);
DISPLAY INVISIBLE (-2915 1160);
FORCEPROP 1 LASTPIN (-2925 1150) BN 4
J 2
(-2873 1158);
DISPLAY 0.617021 (-2873 1158);
PAINT GREEN (-2873 1158);
FORCEPROP 2 LAST CDS_LIB mstr_standard
J 0
(-2875 1150);
PAINT MONO (-2875 1150);
DISPLAY INVISIBLE (-2875 1150);
FORCEPROP 1 LAST BODY_TYPE PLUMBING
J 2
(-2875 1100);
DISPLAY 1.595745 (-2875 1100);
PAINT GREEN (-2875 1100);
DISPLAY INVISIBLE (-2875 1100);
FORCEPROP 1 LAST HDL_TAP TRUE
J 2
(-3200 1025);
DISPLAY 1.595745 (-3200 1025);
PAINT GREEN (-3200 1025);
DISPLAY INVISIBLE (-3200 1025);
FORCEPROP 1 LAST PATH I94
J 2
(-2873 1150);
DISPLAY 0.872340 (-2873 1150);
PAINT GREEN (-2873 1150);
DISPLAY INVISIBLE (-2873 1150);
FORCEADD TAP..6
R 2
(-2875 1100);
FORCEPROP 3 LASTPIN (-2925 1100) SIG_NAME M_M_CS_N<3>
J 0
(-2915 1110);
DISPLAY 0.659574 (-2915 1110);
PAINT MONO (-2915 1110);
DISPLAY INVISIBLE (-2915 1110);
FORCEPROP 1 LASTPIN (-2925 1100) BN 3
J 2
(-2873 1108);
DISPLAY 0.617021 (-2873 1108);
PAINT GREEN (-2873 1108);
FORCEPROP 2 LAST CDS_LIB mstr_standard
J 0
(-2875 1100);
PAINT MONO (-2875 1100);
DISPLAY INVISIBLE (-2875 1100);
FORCEPROP 1 LAST BODY_TYPE PLUMBING
J 2
(-2875 1050);
DISPLAY 1.595745 (-2875 1050);
PAINT GREEN (-2875 1050);
DISPLAY INVISIBLE (-2875 1050);
FORCEPROP 1 LAST HDL_TAP TRUE
J 2
(-3200 975);
DISPLAY 1.595745 (-3200 975);
PAINT GREEN (-3200 975);
DISPLAY INVISIBLE (-3200 975);
FORCEPROP 1 LAST PATH I95
J 2
(-2873 1100);
DISPLAY 0.872340 (-2873 1100);
PAINT GREEN (-2873 1100);
DISPLAY INVISIBLE (-2873 1100);
FORCEADD TAP..6
R 2
(-2875 1200);
FORCEPROP 3 LASTPIN (-2925 1200) SIG_NAME M_M_CS_N<5>
J 0
(-2915 1210);
DISPLAY 0.659574 (-2915 1210);
PAINT MONO (-2915 1210);
DISPLAY INVISIBLE (-2915 1210);
FORCEPROP 1 LASTPIN (-2925 1200) BN 5
J 2
(-2873 1208);
DISPLAY 0.617021 (-2873 1208);
PAINT GREEN (-2873 1208);
FORCEPROP 2 LAST CDS_LIB mstr_standard
J 0
(-2875 1200);
PAINT MONO (-2875 1200);
DISPLAY INVISIBLE (-2875 1200);
FORCEPROP 1 LAST BODY_TYPE PLUMBING
J 2
(-2875 1150);
DISPLAY 1.595745 (-2875 1150);
PAINT GREEN (-2875 1150);
DISPLAY INVISIBLE (-2875 1150);
FORCEPROP 1 LAST HDL_TAP TRUE
J 2
(-3200 1075);
DISPLAY 1.595745 (-3200 1075);
PAINT GREEN (-3200 1075);
DISPLAY INVISIBLE (-3200 1075);
FORCEPROP 1 LAST PATH I96
J 2
(-2873 1200);
DISPLAY 0.872340 (-2873 1200);
PAINT GREEN (-2873 1200);
DISPLAY INVISIBLE (-2873 1200);
FORCEADD TAP..6
R 2
(-2875 1250);
FORCEPROP 3 LASTPIN (-2925 1250) SIG_NAME M_M_CS_N<6>
J 0
(-2915 1260);
DISPLAY 0.659574 (-2915 1260);
PAINT MONO (-2915 1260);
DISPLAY INVISIBLE (-2915 1260);
FORCEPROP 1 LASTPIN (-2925 1250) BN 6
J 2
(-2873 1258);
DISPLAY 0.617021 (-2873 1258);
PAINT GREEN (-2873 1258);
FORCEPROP 2 LAST CDS_LIB mstr_standard
J 0
(-2875 1250);
PAINT MONO (-2875 1250);
DISPLAY INVISIBLE (-2875 1250);
FORCEPROP 1 LAST BODY_TYPE PLUMBING
J 2
(-2875 1200);
DISPLAY 1.595745 (-2875 1200);
PAINT GREEN (-2875 1200);
DISPLAY INVISIBLE (-2875 1200);
FORCEPROP 1 LAST HDL_TAP TRUE
J 2
(-3200 1125);
DISPLAY 1.595745 (-3200 1125);
PAINT GREEN (-3200 1125);
DISPLAY INVISIBLE (-3200 1125);
FORCEPROP 1 LAST PATH I97
J 2
(-2873 1250);
DISPLAY 0.872340 (-2873 1250);
PAINT GREEN (-2873 1250);
DISPLAY INVISIBLE (-2873 1250);
FORCEADD TAP..6
R 2
(-2875 1300);
FORCEPROP 3 LASTPIN (-2925 1300) SIG_NAME M_M_CS_N<7>
J 0
(-2915 1310);
DISPLAY 0.659574 (-2915 1310);
PAINT MONO (-2915 1310);
DISPLAY INVISIBLE (-2915 1310);
FORCEPROP 1 LASTPIN (-2925 1300) BN 7
J 2
(-2873 1308);
DISPLAY 0.617021 (-2873 1308);
PAINT GREEN (-2873 1308);
FORCEPROP 2 LAST CDS_LIB mstr_standard
J 0
(-2875 1300);
PAINT MONO (-2875 1300);
DISPLAY INVISIBLE (-2875 1300);
FORCEPROP 1 LAST BODY_TYPE PLUMBING
J 2
(-2875 1250);
DISPLAY 1.595745 (-2875 1250);
PAINT GREEN (-2875 1250);
DISPLAY INVISIBLE (-2875 1250);
FORCEPROP 1 LAST HDL_TAP TRUE
J 2
(-3200 1175);
DISPLAY 1.595745 (-3200 1175);
PAINT GREEN (-3200 1175);
DISPLAY INVISIBLE (-3200 1175);
FORCEPROP 1 LAST PATH I98
J 2
(-2873 1300);
DISPLAY 0.872340 (-2873 1300);
PAINT GREEN (-2873 1300);
DISPLAY INVISIBLE (-2873 1300);
FORCEADD TAP..6
R 2
(-2875 1400);
FORCEPROP 3 LASTPIN (-2925 1400) SIG_NAME M_M_ODT<0>
J 0
(-2915 1410);
DISPLAY 0.659574 (-2915 1410);
PAINT MONO (-2915 1410);
DISPLAY INVISIBLE (-2915 1410);
FORCEPROP 1 LASTPIN (-2925 1400) BN 0
J 2
(-2873 1408);
DISPLAY 0.617021 (-2873 1408);
PAINT GREEN (-2873 1408);
FORCEPROP 2 LAST CDS_LIB mstr_standard
J 0
(-2875 1400);
PAINT MONO (-2875 1400);
DISPLAY INVISIBLE (-2875 1400);
FORCEPROP 1 LAST BODY_TYPE PLUMBING
J 2
(-2875 1350);
DISPLAY 1.595745 (-2875 1350);
PAINT GREEN (-2875 1350);
DISPLAY INVISIBLE (-2875 1350);
FORCEPROP 1 LAST HDL_TAP TRUE
J 2
(-3200 1275);
DISPLAY 1.595745 (-3200 1275);
PAINT GREEN (-3200 1275);
DISPLAY INVISIBLE (-3200 1275);
FORCEPROP 1 LAST PATH I99
J 2
(-2873 1400);
DISPLAY 0.872340 (-2873 1400);
PAINT GREEN (-2873 1400);
DISPLAY INVISIBLE (-2873 1400);
FORCEADD DESIGN_NOTE..1
(-6400 325);
FORCEPROP 0 LAST L1 CPU SYMBOLS 1-30 ARE PRELIMINARY AND SUBJECT TO CHANGE
J 0
(-6600 200);
DISPLAY 1.021277 (-6600 200);
PAINT ORANGE (-6600 200);
FORCEPROP 2 LAST CDS_LIB mstr_symbols
J 0
(-6400 325);
PAINT ORANGE (-6400 325);
DISPLAY INVISIBLE (-6400 325);
FORCEPROP 1 LAST COMMENT_BODY TRUE
J 0
(-6375 425);
DISPLAY 0.978723 (-6375 425);
PAINT ORANGE (-6375 425);
DISPLAY INVISIBLE (-6375 425);
FORCEADD PRELIM..10
(-4240 2540);
PAINT GRAY (-4240 2540);
FORCEPROP 2 LAST CDS_LIB mstr_misc
J 0
(-4240 2540);
PAINT ORANGE (-4240 2540);
DISPLAY INVISIBLE (-4240 2540);
FORCEPROP 1 LAST COMMENT_BODY TRUE
J 0
(-4240 2540);
PAINT ORANGE (-4240 2540);
DISPLAY INVISIBLE (-4240 2540);
FORCEADD INTEL_CORP_BPAGE..1
(0 0);
FORCEPROP 1 LAST CDS_CON_LAST_MODIFIED Tue Dec 01 11:51:36 2015
J 0
(-1425 325);
DISPLAY 1.340426 (-1425 325);
PAINT GREEN (-1425 325);
DISPLAY INVISIBLE (-1425 325);
FORCEPROP 1 LAST CUSTOM_TXT_CDS <CURRENT_DESIGN_SHEET> OF <TOTAL_DESIGN_SHEETS>
J 0
(-500 25);
PAINT GREEN (-500 25);
FORCEPROP 1 LAST CUSTOM_TXT_CDS <CON_LAST_MODIFIED>
J 0
(-1925 350);
PAINT GREEN (-1925 350);
FORCEPROP 2 LAST CUSTOM_TXT_CDS <XR_PAGE_TITLE>
J 0
(-7890 5250);
DISPLAY 0.638298 (-7890 5250);
PAINT PINK (-7890 5250);
DISPLAY INVISIBLE (-7890 5250);
FORCEPROP 1 LAST SCH_ADDRESS3 Santa Clara, CA 95052-8119
J 0
(-3975 25);
DISPLAY 0.617021 (-3975 25);
PAINT GREEN (-3975 25);
FORCEPROP 1 LAST SCH_ADDRESS2 P.O. BOX 58119
J 0
(-3975 75);
DISPLAY 0.617021 (-3975 75);
PAINT GREEN (-3975 75);
FORCEPROP 1 LAST SCH_ADDRESS1 2200 Mission College Blvd.
J 0
(-3975 125);
DISPLAY 0.617021 (-3975 125);
PAINT GREEN (-3975 125);
FORCEPROP 1 LAST SCH_TITLE SKYLAKE - SKT1 - 8 OF 21
J 0
(-7950 50);
DISPLAY 1.212766 (-7950 50);
PAINT GREEN (-7950 50);
FORCEPROP 1 LAST SCH_NUMBER H4694802
J 0
(-1300 150);
DISPLAY 1.212766 (-1300 150);
PAINT YELLOW (-1300 150);
FORCEPROP 1 LAST SCH_DEPT BESD
J 1
(-4450 100);
DISPLAY 1.212766 (-4450 100);
PAINT YELLOW (-4450 100);
FORCEPROP 1 LAST SCH_REV 2.420
J 0
(-250 150);
DISPLAY 0.978723 (-250 150);
PAINT YELLOW (-250 150);
FORCEPROP 2 LAST PAGE_BORDER TRUE
J 0
(-7890 5250);
DISPLAY 0.851064 (-7890 5250);
PAINT PINK (-7890 5250);
DISPLAY INVISIBLE (-7890 5250);
FORCEPROP 2 LAST CDS_LIB mstr_symbols
J 0
(0 0);
PAINT ORANGE (0 0);
DISPLAY INVISIBLE (0 0);
FORCEPROP 1 LAST COMMENT_BODY TRUE
J 0
(12 12);
DISPLAY 0.638298 (12 12);
PAINT GREEN (12 12);
DISPLAY INVISIBLE (12 12);
FORCEPROP 2 LAST CDS_XR_PAGE_TITLE CR-62 : @BASEBOARD_FAB2_LIB.BASEBOARD_FAB2(SCH_1):PAGE62
J 0
(-7890 5250);
DISPLAY 0.638298 (-7890 5250);
PAINT PINK (-7890 5250);
DISPLAY INVISIBLE (-7890 5250);
WIRE 17 -1 (-2825 4625)(-2825 4675);
WIRE 17 -1 (-2825 4575)(-2825 4625);
WIRE 17 -1 (-2825 4675)(-2825 4725);
WIRE 17 -1 (-2075 4725)(-2825 4725);
FORCEPROP 2 LAST SIG_NAME M_M_DQS_DP<17:0>
J 0
(-2725 4735);
DISPLAY 0.617021 (-2725 4735);
PAINT ORANGE (-2725 4735);
WIRE 17 -1 (-2825 4525)(-2825 4575);
WIRE 17 -1 (-2825 4475)(-2825 4525);
WIRE 17 -1 (-2825 4425)(-2825 4475);
WIRE 17 -1 (-2825 4375)(-2825 4425);
WIRE 17 -1 (-2825 4325)(-2825 4375);
WIRE 17 -1 (-2825 4275)(-2825 4325);
WIRE 17 -1 (-2825 4225)(-2825 4275);
WIRE 17 -1 (-2825 4175)(-2825 4225);
WIRE 17 -1 (-2825 4125)(-2825 4175);
WIRE 17 -1 (-2825 4075)(-2825 4125);
WIRE 17 -1 (-2825 4025)(-2825 4075);
WIRE 17 -1 (-2825 3975)(-2825 4025);
WIRE 17 -1 (-2825 3925)(-2825 3975);
WIRE 17 -1 (-2825 3875)(-2825 3925);
WIRE 17 -1 (-2825 3825)(-2825 3875);
WIRE 17 -1 (-2825 3725)(-2825 3750);
WIRE 17 -1 (-2825 3675)(-2825 3725);
WIRE 17 -1 (-2075 3750)(-2825 3750);
FORCEPROP 2 LAST SIG_NAME M_M_DQS_DN<17:0>
J 0
(-2725 3760);
DISPLAY 0.617021 (-2725 3760);
PAINT ORANGE (-2725 3760);
WIRE 17 -1 (-2825 3625)(-2825 3675);
WIRE 17 -1 (-2825 3575)(-2825 3625);
WIRE 17 -1 (-2825 3525)(-2825 3575);
WIRE 17 -1 (-2825 3475)(-2825 3525);
WIRE 17 -1 (-2825 3425)(-2825 3475);
WIRE 17 -1 (-2825 3375)(-2825 3425);
WIRE 17 -1 (-2825 3325)(-2825 3375);
WIRE 17 -1 (-2825 3275)(-2825 3325);
WIRE 17 -1 (-2825 3225)(-2825 3275);
WIRE 17 -1 (-2825 3175)(-2825 3225);
WIRE 17 -1 (-2825 3125)(-2825 3175);
WIRE 17 -1 (-2825 3075)(-2825 3125);
WIRE 17 -1 (-2825 3025)(-2825 3075);
WIRE 17 -1 (-2825 2975)(-2825 3025);
WIRE 17 -1 (-2825 2925)(-2825 2975);
WIRE 17 -1 (-2825 2875)(-2825 2925);
WIRE 17 -1 (-2825 2775)(-2825 2800);
WIRE 17 -1 (-2825 2725)(-2825 2775);
WIRE 17 -1 (-2075 2800)(-2825 2800);
FORCEPROP 2 LAST SIG_NAME M_M_MA<17:0>
J 0
(-2725 2810);
DISPLAY 0.617021 (-2725 2810);
PAINT ORANGE (-2725 2810);
WIRE 17 -1 (-2825 2675)(-2825 2725);
WIRE 17 -1 (-2825 2625)(-2825 2675);
WIRE 17 -1 (-2825 2575)(-2825 2625);
WIRE 17 -1 (-2825 2525)(-2825 2575);
WIRE 17 -1 (-2825 2475)(-2825 2525);
WIRE 17 -1 (-2825 2425)(-2825 2475);
WIRE 17 -1 (-2825 2375)(-2825 2425);
WIRE 17 -1 (-2825 2325)(-2825 2375);
WIRE 17 -1 (-2825 2275)(-2825 2325);
WIRE 17 -1 (-2825 2225)(-2825 2275);
WIRE 17 -1 (-2825 2175)(-2825 2225);
WIRE 17 -1 (-2825 2125)(-2825 2175);
WIRE 17 -1 (-2825 2075)(-2825 2125);
WIRE 17 -1 (-2825 2025)(-2825 2075);
WIRE 17 -1 (-2825 1975)(-2825 2025);
WIRE 17 -1 (-2825 1925)(-2825 1975);
WIRE 17 -1 (-2825 775)(-2825 800);
WIRE 17 -1 (-2825 725)(-2825 775);
WIRE 17 -1 (-2075 800)(-2825 800);
FORCEPROP 2 LAST SIG_NAME M_M_BA<1:0>
J 0
(-2725 810);
DISPLAY 0.617021 (-2725 810);
PAINT ORANGE (-2725 810);
WIRE 17 -1 (-2825 875)(-2825 900);
WIRE 17 -1 (-2825 825)(-2825 875);
WIRE 17 -1 (-2075 900)(-2825 900);
FORCEPROP 2 LAST SIG_NAME M_M_BG<1:0>
J 0
(-2725 910);
DISPLAY 0.617021 (-2725 910);
PAINT ORANGE (-2725 910);
WIRE 17 -1 (-2825 1825)(-2825 1850);
WIRE 17 -1 (-2825 1775)(-2825 1825);
WIRE 17 -1 (-2075 1850)(-2825 1850);
FORCEPROP 2 LAST SIG_NAME M_M_CKE<3:0>
J 0
(-2725 1860);
DISPLAY 0.617021 (-2725 1860);
PAINT ORANGE (-2725 1860);
WIRE 17 -1 (-2825 1725)(-2825 1775);
WIRE 17 -1 (-2825 1675)(-2825 1725);
WIRE 17 -1 (-2825 1325)(-2825 1350);
WIRE 17 -1 (-2825 1275)(-2825 1325);
WIRE 17 -1 (-2075 1350)(-2825 1350);
FORCEPROP 2 LAST SIG_NAME M_M_CS_N<7:0>
J 0
(-2725 1360);
DISPLAY 0.617021 (-2725 1360);
PAINT ORANGE (-2725 1360);
WIRE 17 -1 (-2825 1225)(-2825 1275);
WIRE 17 -1 (-2825 1175)(-2825 1225);
WIRE 17 -1 (-2825 1125)(-2825 1175);
WIRE 17 -1 (-2825 1075)(-2825 1125);
WIRE 17 -1 (-2825 1025)(-2825 1075);
WIRE 17 -1 (-2825 975)(-2825 1025);
WIRE 17 -1 (-2825 1575)(-2825 1600);
WIRE 17 -1 (-2825 1525)(-2825 1575);
WIRE 17 -1 (-2075 1600)(-2825 1600);
FORCEPROP 2 LAST SIG_NAME M_M_ODT<3:0>
J 0
(-2725 1610);
DISPLAY 0.617021 (-2725 1610);
PAINT ORANGE (-2725 1610);
WIRE 17 -1 (-2825 1475)(-2825 1525);
WIRE 17 -1 (-2825 1425)(-2825 1475);
WIRE 17 -1 (-5650 4625)(-5650 4675);
WIRE 17 -1 (-5650 4575)(-5650 4625);
WIRE 17 -1 (-5650 4675)(-5650 4775);
WIRE 17 -1 (-5650 4775)(-6400 4775);
FORCEPROP 2 LAST SIG_NAME M_M_DQ<63:0>
J 0
(-6350 4785);
DISPLAY 0.617021 (-6350 4785);
PAINT ORANGE (-6350 4785);
WIRE 17 -1 (-5650 4525)(-5650 4575);
WIRE 17 -1 (-5650 4475)(-5650 4525);
WIRE 17 -1 (-5650 4425)(-5650 4475);
WIRE 17 -1 (-5650 4375)(-5650 4425);
WIRE 17 -1 (-5650 4325)(-5650 4375);
WIRE 17 -1 (-5650 4275)(-5650 4325);
WIRE 17 -1 (-5650 4225)(-5650 4275);
WIRE 17 -1 (-5650 4175)(-5650 4225);
WIRE 17 -1 (-5650 4125)(-5650 4175);
WIRE 17 -1 (-5650 4075)(-5650 4125);
WIRE 17 -1 (-5650 4025)(-5650 4075);
WIRE 17 -1 (-5650 3975)(-5650 4025);
WIRE 17 -1 (-5650 3925)(-5650 3975);
WIRE 17 -1 (-5650 3875)(-5650 3925);
WIRE 17 -1 (-5650 3825)(-5650 3875);
WIRE 17 -1 (-5650 3775)(-5650 3825);
WIRE 17 -1 (-5650 3725)(-5650 3775);
WIRE 17 -1 (-5650 3675)(-5650 3725);
WIRE 17 -1 (-5650 3625)(-5650 3675);
WIRE 17 -1 (-5650 3575)(-5650 3625);
WIRE 17 -1 (-5650 3525)(-5650 3575);
WIRE 17 -1 (-5650 3475)(-5650 3525);
WIRE 17 -1 (-5650 3425)(-5650 3475);
WIRE 17 -1 (-5650 3375)(-5650 3425);
WIRE 17 -1 (-5650 3325)(-5650 3375);
WIRE 17 -1 (-5650 3275)(-5650 3325);
WIRE 17 -1 (-5650 3225)(-5650 3275);
WIRE 17 -1 (-5650 3175)(-5650 3225);
WIRE 17 -1 (-5650 3125)(-5650 3175);
WIRE 17 -1 (-5650 3075)(-5650 3125);
WIRE 17 -1 (-5650 3025)(-5650 3075);
WIRE 17 -1 (-5650 2975)(-5650 3025);
WIRE 17 -1 (-5650 2925)(-5650 2975);
WIRE 17 -1 (-5650 2875)(-5650 2925);
WIRE 17 -1 (-5650 2825)(-5650 2875);
WIRE 17 -1 (-5650 2775)(-5650 2825);
WIRE 17 -1 (-5650 2725)(-5650 2775);
WIRE 17 -1 (-5650 2675)(-5650 2725);
WIRE 17 -1 (-5650 2625)(-5650 2675);
WIRE 17 -1 (-5650 2575)(-5650 2625);
WIRE 17 -1 (-5650 2525)(-5650 2575);
WIRE 17 -1 (-5650 2475)(-5650 2525);
WIRE 17 -1 (-5650 2425)(-5650 2475);
WIRE 17 -1 (-5650 2375)(-5650 2425);
WIRE 17 -1 (-5650 2325)(-5650 2375);
WIRE 17 -1 (-5650 2275)(-5650 2325);
WIRE 17 -1 (-5650 2225)(-5650 2275);
WIRE 17 -1 (-5650 2175)(-5650 2225);
WIRE 17 -1 (-5650 2125)(-5650 2175);
WIRE 17 -1 (-5650 2075)(-5650 2125);
WIRE 17 -1 (-5650 2025)(-5650 2075);
WIRE 17 -1 (-5650 1975)(-5650 2025);
WIRE 17 -1 (-5650 1925)(-5650 1975);
WIRE 17 -1 (-5650 1875)(-5650 1925);
WIRE 17 -1 (-5650 1825)(-5650 1875);
WIRE 17 -1 (-5650 1775)(-5650 1825);
WIRE 17 -1 (-5650 1725)(-5650 1775);
WIRE 17 -1 (-5650 1675)(-5650 1725);
WIRE 17 -1 (-5650 1625)(-5650 1675);
WIRE 17 -1 (-5650 1575)(-5650 1625);
WIRE 17 -1 (-5650 1525)(-5650 1575);
WIRE 17 -1 (-5650 775)(-5650 800);
WIRE 17 -1 (-5650 725)(-5650 775);
WIRE 17 -1 (-5650 800)(-6400 800);
FORCEPROP 2 LAST SIG_NAME M_M_CLK_DN<3:0>
J 0
(-6350 810);
DISPLAY 0.617021 (-6350 810);
PAINT ORANGE (-6350 810);
WIRE 17 -1 (-5650 675)(-5650 725);
WIRE 17 -1 (-5650 625)(-5650 675);
WIRE 17 -1 (-5650 975)(-5650 1000);
WIRE 17 -1 (-5650 925)(-5650 975);
WIRE 17 -1 (-5650 1000)(-6400 1000);
FORCEPROP 2 LAST SIG_NAME M_M_CLK_DP<3:0>
J 0
(-6350 1010);
DISPLAY 0.617021 (-6350 1010);
PAINT ORANGE (-6350 1010);
WIRE 17 -1 (-5650 875)(-5650 925);
WIRE 17 -1 (-5650 825)(-5650 875);
WIRE 17 -1 (-5650 1375)(-5650 1425);
WIRE 17 -1 (-5650 1325)(-5650 1375);
WIRE 17 -1 (-5650 1425)(-5650 1450);
WIRE 17 -1 (-5650 1450)(-6400 1450);
FORCEPROP 2 LAST SIG_NAME M_M_ECC<7:0>
J 0
(-6350 1460);
DISPLAY 0.617021 (-6350 1460);
PAINT ORANGE (-6350 1460);
WIRE 17 -1 (-5650 1275)(-5650 1325);
WIRE 17 -1 (-5650 1225)(-5650 1275);
WIRE 17 -1 (-5650 1175)(-5650 1225);
WIRE 17 -1 (-5650 1125)(-5650 1175);
WIRE 17 -1 (-5650 1075)(-5650 1125);
WIRE 16 -1 (-5050 500)(-6400 500);
FORCEPROP 2 LAST SIG_NAME M_M_C<2>
J 0
(-6350 510);
DISPLAY 0.617021 (-6350 510);
PAINT ORANGE (-6350 510);
WIRE 16 -1 (-5050 1050)(-5550 1050);
WIRE 16 -1 (-5050 1100)(-5550 1100);
WIRE 16 -1 (-5050 1150)(-5550 1150);
WIRE 16 -1 (-5050 1200)(-5550 1200);
WIRE 16 -1 (-5050 1250)(-5550 1250);
WIRE 16 -1 (-5050 1300)(-5550 1300);
WIRE 16 -1 (-5050 1350)(-5550 1350);
WIRE 16 -1 (-5050 1400)(-5550 1400);
WIRE 16 -1 (-5550 1500)(-5050 1500);
WIRE 16 -1 (-5550 1550)(-5050 1550);
WIRE 16 -1 (-5550 1600)(-5050 1600);
WIRE 16 -1 (-5050 1650)(-5550 1650);
WIRE 16 -1 (-5550 1700)(-5050 1700);
WIRE 16 -1 (-5550 1750)(-5050 1750);
WIRE 16 -1 (-5050 1800)(-5550 1800);
WIRE 16 -1 (-5550 1850)(-5050 1850);
WIRE 16 -1 (-5550 1900)(-5050 1900);
WIRE 16 -1 (-5550 1950)(-5050 1950);
WIRE 16 -1 (-5550 2000)(-5050 2000);
WIRE 16 -1 (-5050 800)(-5550 800);
WIRE 16 -1 (-5050 850)(-5550 850);
WIRE 16 -1 (-5050 900)(-5550 900);
WIRE 16 -1 (-5050 950)(-5550 950);
WIRE 16 -1 (-5050 600)(-5550 600);
WIRE 16 -1 (-5050 650)(-5550 650);
WIRE 16 -1 (-5050 700)(-5550 700);
WIRE 16 -1 (-5050 750)(-5550 750);
WIRE 16 -1 (-5550 2050)(-5050 2050);
WIRE 16 -1 (-5550 2100)(-5050 2100);
WIRE 16 -1 (-5550 2150)(-5050 2150);
WIRE 16 -1 (-5550 2200)(-5050 2200);
WIRE 16 -1 (-5550 2250)(-5050 2250);
WIRE 16 -1 (-5550 2300)(-5050 2300);
WIRE 16 -1 (-5550 2350)(-5050 2350);
WIRE 16 -1 (-5550 2400)(-5050 2400);
WIRE 16 -1 (-5550 2450)(-5050 2450);
WIRE 16 -1 (-5550 2500)(-5050 2500);
WIRE 16 -1 (-5550 2550)(-5050 2550);
WIRE 16 -1 (-5550 2600)(-5050 2600);
WIRE 16 -1 (-5550 2650)(-5050 2650);
WIRE 16 -1 (-5550 2700)(-5050 2700);
WIRE 16 -1 (-5550 2750)(-5050 2750);
WIRE 16 -1 (-5550 2800)(-5050 2800);
WIRE 16 -1 (-5550 2850)(-5050 2850);
WIRE 16 -1 (-5550 2900)(-5050 2900);
WIRE 16 -1 (-5550 2950)(-5050 2950);
WIRE 16 -1 (-5550 3000)(-5050 3000);
WIRE 16 -1 (-5550 3050)(-5050 3050);
WIRE 16 -1 (-5550 3100)(-5050 3100);
WIRE 16 -1 (-5550 3150)(-5050 3150);
WIRE 16 -1 (-5550 3200)(-5050 3200);
WIRE 16 -1 (-5550 3250)(-5050 3250);
WIRE 16 -1 (-5550 3300)(-5050 3300);
WIRE 16 -1 (-5050 3350)(-5550 3350);
WIRE 16 -1 (-5550 3400)(-5050 3400);
WIRE 16 -1 (-5550 3450)(-5050 3450);
WIRE 16 -1 (-5050 3500)(-5550 3500);
WIRE 16 -1 (-5550 3550)(-5050 3550);
WIRE 16 -1 (-5550 3600)(-5050 3600);
WIRE 16 -1 (-5050 3650)(-5550 3650);
WIRE 16 -1 (-5050 3700)(-5550 3700);
WIRE 16 -1 (-5050 3750)(-5550 3750);
WIRE 16 -1 (-5050 3800)(-5550 3800);
WIRE 16 -1 (-5050 3850)(-5550 3850);
WIRE 16 -1 (-5050 3900)(-5550 3900);
WIRE 16 -1 (-5050 3950)(-5550 3950);
WIRE 16 -1 (-5050 4000)(-5550 4000);
WIRE 16 -1 (-5050 4050)(-5550 4050);
WIRE 16 -1 (-5050 4100)(-5550 4100);
WIRE 16 -1 (-5050 4150)(-5550 4150);
WIRE 16 -1 (-5050 4200)(-5550 4200);
WIRE 16 -1 (-5050 4250)(-5550 4250);
WIRE 16 -1 (-5050 4300)(-5550 4300);
WIRE 16 -1 (-5050 4350)(-5550 4350);
WIRE 16 -1 (-5050 4400)(-5550 4400);
WIRE 16 -1 (-5050 4450)(-5550 4450);
WIRE 16 -1 (-5050 4500)(-5550 4500);
WIRE 16 -1 (-5050 4550)(-5550 4550);
WIRE 16 -1 (-5050 4600)(-5550 4600);
WIRE 16 -1 (-5050 4650)(-5550 4650);
WIRE 16 -1 (-3350 1400)(-2925 1400);
WIRE 16 -1 (-3350 1450)(-2925 1450);
WIRE 16 -1 (-3350 1500)(-2925 1500);
WIRE 16 -1 (-3350 1550)(-2925 1550);
WIRE 16 -1 (-3350 1900)(-2925 1900);
WIRE 16 -1 (-3350 1950)(-2925 1950);
WIRE 16 -1 (-3350 2000)(-2925 2000);
WIRE 16 -1 (-3350 950)(-2925 950);
WIRE 16 -1 (-3350 1000)(-2925 1000);
WIRE 16 -1 (-3350 1050)(-2925 1050);
WIRE 16 -1 (-3350 1100)(-2925 1100);
WIRE 16 -1 (-3350 1150)(-2925 1150);
WIRE 16 -1 (-3350 1200)(-2925 1200);
WIRE 16 -1 (-3350 1250)(-2925 1250);
WIRE 16 -1 (-3350 1300)(-2925 1300);
WIRE 16 -1 (-3350 1650)(-2925 1650);
WIRE 16 -1 (-3350 1700)(-2925 1700);
WIRE 16 -1 (-3350 1750)(-2925 1750);
WIRE 16 -1 (-3350 1800)(-2925 1800);
WIRE 16 -1 (-3350 800)(-2925 800);
WIRE 16 -1 (-3350 850)(-2925 850);
WIRE 16 -1 (-3350 700)(-2925 700);
WIRE 16 -1 (-3350 750)(-2925 750);
WIRE 16 -1 (-2075 500)(-3350 500);
FORCEPROP 2 LAST SIG_NAME M_M_PAR
J 0
(-2725 510);
DISPLAY 0.617021 (-2725 510);
PAINT ORANGE (-2725 510);
WIRE 16 -1 (-2075 600)(-3350 600);
FORCEPROP 2 LAST SIG_NAME M_M_ACT_N
J 0
(-2725 610);
DISPLAY 0.617021 (-2725 610);
PAINT ORANGE (-2725 610);
WIRE 16 -1 (-2075 550)(-3350 550);
FORCEPROP 2 LAST SIG_NAME M_M_ALERT_N
J 0
(-2725 560);
DISPLAY 0.617021 (-2725 560);
PAINT ORANGE (-2725 560);
WIRE 16 -1 (-3350 2050)(-2925 2050);
WIRE 16 -1 (-2925 2100)(-3350 2100);
WIRE 16 -1 (-3350 2150)(-2925 2150);
WIRE 16 -1 (-3350 2200)(-2925 2200);
WIRE 16 -1 (-2925 2250)(-3350 2250);
WIRE 16 -1 (-3350 2300)(-2925 2300);
WIRE 16 -1 (-2925 2350)(-3350 2350);
WIRE 16 -1 (-2925 2400)(-3350 2400);
WIRE 16 -1 (-3350 2450)(-2925 2450);
WIRE 16 -1 (-2925 2500)(-3350 2500);
WIRE 16 -1 (-2925 2550)(-3350 2550);
WIRE 16 -1 (-2925 2600)(-3350 2600);
WIRE 16 -1 (-2925 2650)(-3350 2650);
WIRE 16 -1 (-3350 2700)(-2925 2700);
WIRE 16 -1 (-2925 2750)(-3350 2750);
WIRE 16 -1 (-3350 3800)(-2925 3800);
WIRE 16 -1 (-3350 3850)(-2925 3850);
WIRE 16 -1 (-3350 3900)(-2925 3900);
WIRE 16 -1 (-3350 3950)(-2925 3950);
WIRE 16 -1 (-3350 4000)(-2925 4000);
WIRE 16 -1 (-3350 4050)(-2925 4050);
WIRE 16 -1 (-3350 2850)(-2925 2850);
WIRE 16 -1 (-2925 2900)(-3350 2900);
WIRE 16 -1 (-2925 2950)(-3350 2950);
WIRE 16 -1 (-2925 3000)(-3350 3000);
WIRE 16 -1 (-2925 3050)(-3350 3050);
WIRE 16 -1 (-3350 3100)(-2925 3100);
WIRE 16 -1 (-2925 3150)(-3350 3150);
WIRE 16 -1 (-2925 3200)(-3350 3200);
WIRE 16 -1 (-2925 3250)(-3350 3250);
WIRE 16 -1 (-2925 3300)(-3350 3300);
WIRE 16 -1 (-3350 3350)(-2925 3350);
WIRE 16 -1 (-3350 3400)(-2925 3400);
WIRE 16 -1 (-3350 3450)(-2925 3450);
WIRE 16 -1 (-3350 3500)(-2925 3500);
WIRE 16 -1 (-3350 3550)(-2925 3550);
WIRE 16 -1 (-3350 3600)(-2925 3600);
WIRE 16 -1 (-3350 3650)(-2925 3650);
WIRE 16 -1 (-3350 3700)(-2925 3700);
WIRE 16 -1 (-3350 4100)(-2925 4100);
WIRE 16 -1 (-3350 4150)(-2925 4150);
WIRE 16 -1 (-3350 4200)(-2925 4200);
WIRE 16 -1 (-3350 4250)(-2925 4250);
WIRE 16 -1 (-3350 4300)(-2925 4300);
WIRE 16 -1 (-3350 4350)(-2925 4350);
WIRE 16 -1 (-3350 4400)(-2925 4400);
WIRE 16 -1 (-3350 4450)(-2925 4450);
WIRE 16 -1 (-3350 4500)(-2925 4500);
WIRE 16 -1 (-3350 4550)(-2925 4550);
WIRE 16 -1 (-3350 4600)(-2925 4600);
WIRE 16 -1 (-3350 4650)(-2925 4650);
FORCENOTE
BOM_COST=PROC_SOCKET
(-7950 250) 0;
DISPLAY LEFT (-7950 250);
DISPLAY 1.723404 (-7950 250);
PAINT PURPLE (-7950 250);
FORCENOTE
ROOM=CPU1
(-7950 375) 0;
DISPLAY LEFT (-7950 375);
DISPLAY 1.723404 (-7950 375);
PAINT PURPLE (-7950 375);
QUIT
